FILE_TYPE = MACRO_DRAWING;
SET COLOR_WIRE YELLOW;
SET COLOR_PROP MONO;
SET COLOR_DOT WHITE;
SET COLOR_ARC YELLOW;
SET COLOR_BODY GREEN;
SET COLOR_NOTE MONO;
SET PROP_DISPLAY VALUE;
SET PAGE_NUMBER P105;
FORCEADD CAP..1
R 2
(1125 3650);
FORCEPROP 1 LASTPIN (1125 3550) $PN 2
J 2
(1115 3530);
DISPLAY 0.617021 (1115 3530);
PAINT ORANGE (1115 3530);
FORCEPROP 1 LAST PACK_TYPE 0402
J 2
(1075 3450);
DISPLAY 0.617021 (1075 3450);
PAINT SKYBLUE (1075 3450);
FORCEPROP 1 LAST PART_NUMBER A36096-155
J 2
(1075 3500);
DISPLAY 0.617021 (1075 3500);
PAINT BLUE (1075 3500);
FORCEPROP 1 LAST MATERIAL X7R
J 2
(1075 3550);
DISPLAY 0.617021 (1075 3550);
PAINT SKYBLUE (1075 3550);
FORCEPROP 1 LASTPIN (1125 3750) $PN 1
J 2
(1115 3730);
DISPLAY 0.617021 (1115 3730);
PAINT ORANGE (1115 3730);
FORCEPROP 1 LAST LOCATION C7G24
J 2
(1075 3750);
DISPLAY 0.617021 (1075 3750);
PAINT AQUA (1075 3750);
FORCEPROP 1 LAST VOLTAGE 16V
J 2
(1075 3650);
DISPLAY 0.617021 (1075 3650);
PAINT SKYBLUE (1075 3650);
FORCEPROP 1 LAST TOLERANCE 10%
J 2
(1075 3600);
DISPLAY 0.617021 (1075 3600);
PAINT SKYBLUE (1075 3600);
FORCEPROP 1 LAST VALUE 0.22UF
J 2
(1075 3700);
DISPLAY 0.617021 (1075 3700);
PAINT SKYBLUE (1075 3700);
FORCEPROP 2 LAST ROOM OCP_STEERING
J 2
(1125 3650);
PAINT MONO (1125 3650);
DISPLAY INVISIBLE (1125 3650);
FORCEPROP 1 LAST PATH I1
J 2
(1075 3800);
DISPLAY 0.978723 (1075 3800);
PAINT WHITE (1075 3800);
DISPLAY INVISIBLE (1075 3800);
FORCEPROP 2 LAST CDS_LOCATION C7G24
J 2
(1075 3750);
DISPLAY 0.617021 (1075 3750);
PAINT AQUA (1075 3750);
DISPLAY INVISIBLE (1075 3750);
FORCEPROP 2 LAST SEC 1
J 0
(1075 3850);
DISPLAY 0.680851 (1075 3850);
PAINT MONO (1075 3850);
DISPLAY INVISIBLE (1075 3850);
FORCEPROP 2 LAST SEC_TYPE 0402
J 0
(1075 3850);
DISPLAY 1.021277 (1075 3850);
PAINT ORANGE (1075 3850);
DISPLAY INVISIBLE (1075 3850);
FORCEPROP 2 LAST CDS_LIB mstr_discrete
J 0
(1125 3650);
PAINT ORANGE (1125 3650);
DISPLAY INVISIBLE (1125 3650);
FORCEADD TAP..7
(-100 3100);
FORCEPROP 3 LASTPIN (-100 3150) SIG_NAME P3E_CPU0_PE2_SS_C_TXN<12>
J 0
(-90 3160);
DISPLAY 0.659574 (-90 3160);
PAINT MONO (-90 3160);
DISPLAY INVISIBLE (-90 3160);
FORCEPROP 1 LASTPIN (-100 3150) BN 12
R 1
J 0
(-107 3098);
DISPLAY 0.617021 (-107 3098);
PAINT GREEN (-107 3098);
FORCEPROP 1 LAST PATH I10
J 0
(-102 3100);
DISPLAY 0.872340 (-102 3100);
PAINT GREEN (-102 3100);
DISPLAY INVISIBLE (-102 3100);
FORCEPROP 2 LAST CDS_LIB mstr_standard
J 0
(-100 3100);
PAINT ORANGE (-100 3100);
DISPLAY INVISIBLE (-100 3100);
FORCEPROP 1 LAST BODY_TYPE PLUMBING
J 0
(-50 3100);
DISPLAY 2.276596 (-50 3100);
PAINT GREEN (-50 3100);
DISPLAY INVISIBLE (-50 3100);
FORCEPROP 1 LAST HDL_TAP TRUE
J 0
(220 2970);
DISPLAY 2.276596 (220 2970);
PAINT GREEN (220 2970);
DISPLAY INVISIBLE (220 2970);
FORCEADD TAP..7
(100 3100);
FORCEPROP 3 LASTPIN (100 3150) SIG_NAME P3E_CPU0_PE2_SS_C_TXN<11>
J 0
(110 3160);
DISPLAY 0.659574 (110 3160);
PAINT MONO (110 3160);
DISPLAY INVISIBLE (110 3160);
FORCEPROP 1 LASTPIN (100 3150) BN 11
R 1
J 0
(93 3098);
DISPLAY 0.617021 (93 3098);
PAINT GREEN (93 3098);
FORCEPROP 1 LAST PATH I11
J 0
(98 3100);
DISPLAY 0.872340 (98 3100);
PAINT GREEN (98 3100);
DISPLAY INVISIBLE (98 3100);
FORCEPROP 2 LAST CDS_LIB mstr_standard
J 0
(100 3100);
PAINT ORANGE (100 3100);
DISPLAY INVISIBLE (100 3100);
FORCEPROP 1 LAST BODY_TYPE PLUMBING
J 0
(150 3100);
DISPLAY 2.276596 (150 3100);
PAINT GREEN (150 3100);
DISPLAY INVISIBLE (150 3100);
FORCEPROP 1 LAST HDL_TAP TRUE
J 0
(420 2970);
DISPLAY 2.276596 (420 2970);
PAINT GREEN (420 2970);
DISPLAY INVISIBLE (420 2970);
FORCEADD CAP..1
R 2
(-100 3650);
FORCEPROP 1 LASTPIN (-100 3750) $PN 1
J 2
(-110 3730);
DISPLAY 0.617021 (-110 3730);
PAINT ORANGE (-110 3730);
FORCEPROP 1 LASTPIN (-100 3550) $PN 2
J 2
(-110 3530);
DISPLAY 0.617021 (-110 3530);
PAINT ORANGE (-110 3530);
FORCEPROP 1 LAST MATERIAL X7R
J 2
(-150 3550);
DISPLAY 0.617021 (-150 3550);
PAINT SKYBLUE (-150 3550);
FORCEPROP 1 LAST VOLTAGE 16V
J 2
(-150 3650);
DISPLAY 0.617021 (-150 3650);
PAINT SKYBLUE (-150 3650);
FORCEPROP 1 LAST PACK_TYPE 0402
J 2
(-150 3450);
DISPLAY 0.617021 (-150 3450);
PAINT SKYBLUE (-150 3450);
FORCEPROP 1 LAST TOLERANCE 10%
J 2
(-150 3600);
DISPLAY 0.617021 (-150 3600);
PAINT SKYBLUE (-150 3600);
FORCEPROP 1 LAST VALUE 0.22UF
J 2
(-150 3700);
DISPLAY 0.617021 (-150 3700);
PAINT SKYBLUE (-150 3700);
FORCEPROP 1 LAST PART_NUMBER A36096-155
J 2
(-150 3500);
DISPLAY 0.617021 (-150 3500);
PAINT BLUE (-150 3500);
FORCEPROP 1 LAST LOCATION C7G12
J 2
(-150 3750);
DISPLAY 0.617021 (-150 3750);
PAINT AQUA (-150 3750);
FORCEPROP 2 LAST ROOM OCP_STEERING
J 2
(-100 3650);
PAINT MONO (-100 3650);
DISPLAY INVISIBLE (-100 3650);
FORCEPROP 1 LAST PATH I12
J 2
(-150 3800);
DISPLAY 0.978723 (-150 3800);
PAINT WHITE (-150 3800);
DISPLAY INVISIBLE (-150 3800);
FORCEPROP 2 LAST CDS_LOCATION C7G12
J 2
(-150 3750);
DISPLAY 0.617021 (-150 3750);
PAINT AQUA (-150 3750);
DISPLAY INVISIBLE (-150 3750);
FORCEPROP 2 LAST SEC 1
J 0
(-150 3850);
DISPLAY 0.680851 (-150 3850);
PAINT MONO (-150 3850);
DISPLAY INVISIBLE (-150 3850);
FORCEPROP 2 LAST CDS_LIB mstr_discrete
J 0
(-100 3650);
PAINT ORANGE (-100 3650);
DISPLAY INVISIBLE (-100 3650);
FORCEPROP 2 LAST SEC_TYPE 0402
J 0
(-150 3850);
DISPLAY 1.021277 (-150 3850);
PAINT ORANGE (-150 3850);
DISPLAY INVISIBLE (-150 3850);
FORCEADD CAP..1
R 2
(100 3350);
FORCEPROP 1 LASTPIN (100 3450) $PN 1
J 2
(90 3430);
DISPLAY 0.617021 (90 3430);
PAINT ORANGE (90 3430);
FORCEPROP 1 LASTPIN (100 3250) $PN 2
J 2
(90 3230);
DISPLAY 0.617021 (90 3230);
PAINT ORANGE (90 3230);
FORCEPROP 1 LAST MATERIAL X7R
J 2
(50 3250);
DISPLAY 0.617021 (50 3250);
PAINT SKYBLUE (50 3250);
FORCEPROP 1 LAST VOLTAGE 16V
J 2
(50 3350);
DISPLAY 0.617021 (50 3350);
PAINT SKYBLUE (50 3350);
FORCEPROP 1 LAST PACK_TYPE 0402
J 2
(50 3150);
DISPLAY 0.617021 (50 3150);
PAINT SKYBLUE (50 3150);
FORCEPROP 1 LAST TOLERANCE 10%
J 2
(50 3300);
DISPLAY 0.617021 (50 3300);
PAINT SKYBLUE (50 3300);
FORCEPROP 1 LAST VALUE 0.22UF
J 2
(50 3400);
DISPLAY 0.617021 (50 3400);
PAINT SKYBLUE (50 3400);
FORCEPROP 1 LAST PART_NUMBER A36096-155
J 2
(50 3200);
DISPLAY 0.617021 (50 3200);
PAINT BLUE (50 3200);
FORCEPROP 1 LAST LOCATION C7G13
J 2
(50 3450);
DISPLAY 0.617021 (50 3450);
PAINT AQUA (50 3450);
FORCEPROP 2 LAST ROOM OCP_STEERING
J 2
(100 3350);
PAINT MONO (100 3350);
DISPLAY INVISIBLE (100 3350);
FORCEPROP 1 LAST PATH I13
J 2
(50 3500);
DISPLAY 0.978723 (50 3500);
PAINT WHITE (50 3500);
DISPLAY INVISIBLE (50 3500);
FORCEPROP 2 LAST CDS_LOCATION C7G13
J 2
(50 3450);
DISPLAY 0.617021 (50 3450);
PAINT AQUA (50 3450);
DISPLAY INVISIBLE (50 3450);
FORCEPROP 2 LAST SEC 1
J 0
(50 3550);
DISPLAY 0.680851 (50 3550);
PAINT MONO (50 3550);
DISPLAY INVISIBLE (50 3550);
FORCEPROP 2 LAST CDS_LIB mstr_discrete
J 0
(100 3350);
PAINT ORANGE (100 3350);
DISPLAY INVISIBLE (100 3350);
FORCEPROP 2 LAST SEC_TYPE 0402
J 0
(50 3550);
DISPLAY 1.021277 (50 3550);
PAINT ORANGE (50 3550);
DISPLAY INVISIBLE (50 3550);
FORCEADD TAP..3
(-700 3900);
FORCEPROP 3 LASTPIN (-700 3850) SIG_NAME P3E_CPU0_PE2_SS_TXN<15>
J 0
(-690 3860);
DISPLAY 0.659574 (-690 3860);
PAINT MONO (-690 3860);
DISPLAY INVISIBLE (-690 3860);
FORCEPROP 1 LASTPIN (-700 3850) BN 15
R 1
J 0
(-707 3838);
DISPLAY 0.617021 (-707 3838);
PAINT GREEN (-707 3838);
FORCEPROP 1 LAST PATH I14
J 0
(-702 3900);
DISPLAY 0.872340 (-702 3900);
PAINT GREEN (-702 3900);
DISPLAY INVISIBLE (-702 3900);
FORCEPROP 2 LAST CDS_LIB mstr_standard
J 0
(-700 3900);
PAINT ORANGE (-700 3900);
DISPLAY INVISIBLE (-700 3900);
FORCEPROP 1 LAST BODY_TYPE PLUMBING
J 0
(-650 3850);
DISPLAY 2.276596 (-650 3850);
PAINT GREEN (-650 3850);
DISPLAY INVISIBLE (-650 3850);
FORCEPROP 1 LAST HDL_TAP TRUE
J 0
(-380 3770);
DISPLAY 2.276596 (-380 3770);
PAINT GREEN (-380 3770);
DISPLAY INVISIBLE (-380 3770);
FORCEADD TAP..7
(-750 4100);
FORCEPROP 3 LASTPIN (-750 4150) SIG_NAME P3E_CPU0_PE2_SS_C_TXP<15>
J 0
(-740 4160);
DISPLAY 0.659574 (-740 4160);
PAINT MONO (-740 4160);
DISPLAY INVISIBLE (-740 4160);
FORCEPROP 1 LASTPIN (-750 4150) BN 15
R 1
J 0
(-757 4098);
DISPLAY 0.617021 (-757 4098);
PAINT GREEN (-757 4098);
FORCEPROP 1 LAST PATH I15
J 0
(-752 4100);
DISPLAY 0.872340 (-752 4100);
PAINT GREEN (-752 4100);
DISPLAY INVISIBLE (-752 4100);
FORCEPROP 2 LAST CDS_LIB mstr_standard
J 0
(-750 4100);
PAINT ORANGE (-750 4100);
DISPLAY INVISIBLE (-750 4100);
FORCEPROP 1 LAST BODY_TYPE PLUMBING
J 0
(-700 4100);
DISPLAY 2.276596 (-700 4100);
PAINT GREEN (-700 4100);
DISPLAY INVISIBLE (-700 4100);
FORCEPROP 1 LAST HDL_TAP TRUE
J 0
(-430 3970);
DISPLAY 2.276596 (-430 3970);
PAINT GREEN (-430 3970);
DISPLAY INVISIBLE (-430 3970);
FORCEADD TAP..3
(1925 3900);
FORCEPROP 3 LASTPIN (1925 3850) SIG_NAME P3E_CPU0_PE2_SS_TXN<2>
J 0
(1935 3860);
DISPLAY 0.659574 (1935 3860);
PAINT MONO (1935 3860);
DISPLAY INVISIBLE (1935 3860);
FORCEPROP 1 LASTPIN (1925 3850) BN 2
R 1
J 0
(1918 3838);
DISPLAY 0.617021 (1918 3838);
PAINT GREEN (1918 3838);
FORCEPROP 1 LAST PATH I151
J 0
(1923 3900);
DISPLAY 0.872340 (1923 3900);
PAINT GREEN (1923 3900);
DISPLAY INVISIBLE (1923 3900);
FORCEPROP 2 LAST CDS_LIB mstr_standard
J 0
(1925 3900);
PAINT ORANGE (1925 3900);
DISPLAY INVISIBLE (1925 3900);
FORCEPROP 1 LAST BODY_TYPE PLUMBING
J 0
(1975 3850);
DISPLAY 2.276596 (1975 3850);
PAINT GREEN (1975 3850);
DISPLAY INVISIBLE (1975 3850);
FORCEPROP 1 LAST HDL_TAP TRUE
J 0
(2245 3770);
DISPLAY 2.276596 (2245 3770);
PAINT GREEN (2245 3770);
DISPLAY INVISIBLE (2245 3770);
FORCEADD TAP..3
(50 4900);
FORCEPROP 3 LASTPIN (50 4850) SIG_NAME P3E_CPU0_PE2_SS_TXP<11>
J 0
(60 4860);
DISPLAY 0.659574 (60 4860);
PAINT MONO (60 4860);
DISPLAY INVISIBLE (60 4860);
FORCEPROP 1 LASTPIN (50 4850) BN 11
R 1
J 0
(43 4838);
DISPLAY 0.617021 (43 4838);
PAINT GREEN (43 4838);
FORCEPROP 1 LAST PATH I152
J 0
(48 4900);
DISPLAY 0.872340 (48 4900);
PAINT GREEN (48 4900);
DISPLAY INVISIBLE (48 4900);
FORCEPROP 2 LAST CDS_LIB mstr_standard
J 0
(50 4900);
PAINT ORANGE (50 4900);
DISPLAY INVISIBLE (50 4900);
FORCEPROP 1 LAST BODY_TYPE PLUMBING
J 0
(100 4850);
DISPLAY 2.276596 (100 4850);
PAINT GREEN (100 4850);
DISPLAY INVISIBLE (100 4850);
FORCEPROP 1 LAST HDL_TAP TRUE
J 0
(370 4770);
DISPLAY 2.276596 (370 4770);
PAINT GREEN (370 4770);
DISPLAY INVISIBLE (370 4770);
FORCEADD CAP..1
R 2
(-1500 975);
FORCEPROP 0 LAST GROUP PCIE_UPLINK
J 0
(-1650 700);
DISPLAY 0.638298 (-1650 700);
PAINT BROWN (-1650 700);
DISPLAY BOTH (-1650 700);
FORCEPROP 1 LASTPIN (-1500 1075) $PN 1
J 2
(-1510 1055);
DISPLAY 0.617021 (-1510 1055);
PAINT ORANGE (-1510 1055);
FORCEPROP 1 LASTPIN (-1500 875) $PN 2
J 2
(-1510 855);
DISPLAY 0.617021 (-1510 855);
PAINT ORANGE (-1510 855);
FORCEPROP 1 LAST MATERIAL X7R
J 2
(-1550 875);
DISPLAY 0.617021 (-1550 875);
PAINT SKYBLUE (-1550 875);
FORCEPROP 1 LAST VOLTAGE 16V
J 2
(-1550 975);
DISPLAY 0.617021 (-1550 975);
PAINT SKYBLUE (-1550 975);
FORCEPROP 1 LAST PACK_TYPE 0402
J 2
(-1550 775);
DISPLAY 0.617021 (-1550 775);
PAINT SKYBLUE (-1550 775);
FORCEPROP 1 LAST TOLERANCE 10%
J 2
(-1550 925);
DISPLAY 0.617021 (-1550 925);
PAINT SKYBLUE (-1550 925);
FORCEPROP 1 LAST VALUE 0.22UF
J 2
(-1550 1025);
DISPLAY 0.617021 (-1550 1025);
PAINT SKYBLUE (-1550 1025);
FORCEPROP 1 LAST LOCATION C6B18
J 2
(-1550 1075);
DISPLAY 0.617021 (-1550 1075);
PAINT AQUA (-1550 1075);
FORCEPROP 1 LAST PART_NUMBER A36096-155
J 2
(-1550 825);
DISPLAY 0.617021 (-1550 825);
PAINT BLUE (-1550 825);
FORCEPROP 2 LAST ROOM OCP_STEERING
J 2
(-1500 975);
PAINT MONO (-1500 975);
DISPLAY INVISIBLE (-1500 975);
FORCEPROP 1 LAST PATH I153
J 2
(-1550 1125);
DISPLAY 0.978723 (-1550 1125);
PAINT WHITE (-1550 1125);
DISPLAY INVISIBLE (-1550 1125);
FORCEPROP 2 LAST CDS_LOCATION C6B18
J 2
(-1550 1075);
DISPLAY 0.617021 (-1550 1075);
PAINT AQUA (-1550 1075);
DISPLAY INVISIBLE (-1550 1075);
FORCEPROP 2 LAST SEC 1
J 0
(-1550 1175);
DISPLAY 0.680851 (-1550 1175);
PAINT MONO (-1550 1175);
DISPLAY INVISIBLE (-1550 1175);
FORCEPROP 2 LAST CDS_LIB mstr_discrete
J 0
(-1500 975);
PAINT ORANGE (-1500 975);
DISPLAY INVISIBLE (-1500 975);
FORCEPROP 2 LAST SEC_TYPE 0402
J 0
(-1550 1175);
DISPLAY 1.021277 (-1550 1175);
PAINT ORANGE (-1550 1175);
DISPLAY INVISIBLE (-1550 1175);
FORCEADD TAP..7
(-1350 1725);
FORCEPROP 3 LASTPIN (-1350 1775) SIG_NAME P3E_CPU0_PE1_PCH_C_TXN<8>
J 0
(-1340 1785);
DISPLAY 0.659574 (-1340 1785);
PAINT MONO (-1340 1785);
DISPLAY INVISIBLE (-1340 1785);
FORCEPROP 1 LASTPIN (-1350 1775) BN 8
R 1
J 0
(-1357 1723);
DISPLAY 0.617021 (-1357 1723);
PAINT GREEN (-1357 1723);
FORCEPROP 1 LAST PATH I154
J 0
(-1352 1725);
DISPLAY 0.872340 (-1352 1725);
PAINT GREEN (-1352 1725);
DISPLAY INVISIBLE (-1352 1725);
FORCEPROP 2 LAST CDS_LIB mstr_standard
J 0
(-1350 1725);
PAINT ORANGE (-1350 1725);
DISPLAY INVISIBLE (-1350 1725);
FORCEPROP 1 LAST BODY_TYPE PLUMBING
J 0
(-1300 1725);
DISPLAY 2.276596 (-1300 1725);
PAINT GREEN (-1300 1725);
DISPLAY INVISIBLE (-1300 1725);
FORCEPROP 1 LAST HDL_TAP TRUE
J 0
(-1030 1595);
DISPLAY 2.276596 (-1030 1595);
PAINT GREEN (-1030 1595);
DISPLAY INVISIBLE (-1030 1595);
FORCEADD TAP..3
(-2100 1525);
FORCEPROP 3 LASTPIN (-2100 1475) SIG_NAME P3E_CPU0_PE1_PCH_TXP<12>
J 0
(-2090 1485);
DISPLAY 0.659574 (-2090 1485);
PAINT MONO (-2090 1485);
DISPLAY INVISIBLE (-2090 1485);
FORCEPROP 1 LASTPIN (-2100 1475) BN 12
R 1
J 0
(-2107 1463);
DISPLAY 0.617021 (-2107 1463);
PAINT GREEN (-2107 1463);
FORCEPROP 1 LAST PATH I155
J 0
(-2102 1525);
DISPLAY 0.872340 (-2102 1525);
PAINT GREEN (-2102 1525);
DISPLAY INVISIBLE (-2102 1525);
FORCEPROP 2 LAST CDS_LIB mstr_standard
J 0
(-2100 1525);
PAINT ORANGE (-2100 1525);
DISPLAY INVISIBLE (-2100 1525);
FORCEPROP 1 LAST BODY_TYPE PLUMBING
J 0
(-2050 1475);
DISPLAY 2.276596 (-2050 1475);
PAINT GREEN (-2050 1475);
DISPLAY INVISIBLE (-2050 1475);
FORCEPROP 1 LAST HDL_TAP TRUE
J 0
(-1780 1395);
DISPLAY 2.276596 (-1780 1395);
PAINT GREEN (-1780 1395);
DISPLAY INVISIBLE (-1780 1395);
FORCEADD TAP..7
(-2350 1725);
FORCEPROP 3 LASTPIN (-2350 1775) SIG_NAME P3E_CPU0_PE1_PCH_C_TXN<13>
J 0
(-2340 1785);
DISPLAY 0.659574 (-2340 1785);
PAINT MONO (-2340 1785);
DISPLAY INVISIBLE (-2340 1785);
FORCEPROP 1 LASTPIN (-2350 1775) BN 13
R 1
J 0
(-2357 1723);
DISPLAY 0.617021 (-2357 1723);
PAINT GREEN (-2357 1723);
FORCEPROP 1 LAST PATH I156
J 0
(-2352 1725);
DISPLAY 0.872340 (-2352 1725);
PAINT GREEN (-2352 1725);
DISPLAY INVISIBLE (-2352 1725);
FORCEPROP 2 LAST CDS_LIB mstr_standard
J 0
(-2350 1725);
PAINT ORANGE (-2350 1725);
DISPLAY INVISIBLE (-2350 1725);
FORCEPROP 1 LAST BODY_TYPE PLUMBING
J 0
(-2300 1725);
DISPLAY 2.276596 (-2300 1725);
PAINT GREEN (-2300 1725);
DISPLAY INVISIBLE (-2300 1725);
FORCEPROP 1 LAST HDL_TAP TRUE
J 0
(-2030 1595);
DISPLAY 2.276596 (-2030 1595);
PAINT GREEN (-2030 1595);
DISPLAY INVISIBLE (-2030 1595);
FORCEADD TAP..7
(-2550 1725);
FORCEPROP 3 LASTPIN (-2550 1775) SIG_NAME P3E_CPU0_PE1_PCH_C_TXN<14>
J 0
(-2540 1785);
DISPLAY 0.659574 (-2540 1785);
PAINT MONO (-2540 1785);
DISPLAY INVISIBLE (-2540 1785);
FORCEPROP 1 LASTPIN (-2550 1775) BN 14
R 1
J 0
(-2557 1723);
DISPLAY 0.617021 (-2557 1723);
PAINT GREEN (-2557 1723);
FORCEPROP 1 LAST PATH I157
J 0
(-2552 1725);
DISPLAY 0.872340 (-2552 1725);
PAINT GREEN (-2552 1725);
DISPLAY INVISIBLE (-2552 1725);
FORCEPROP 2 LAST CDS_LIB mstr_standard
J 0
(-2550 1725);
PAINT ORANGE (-2550 1725);
DISPLAY INVISIBLE (-2550 1725);
FORCEPROP 1 LAST BODY_TYPE PLUMBING
J 0
(-2500 1725);
DISPLAY 2.276596 (-2500 1725);
PAINT GREEN (-2500 1725);
DISPLAY INVISIBLE (-2500 1725);
FORCEPROP 1 LAST HDL_TAP TRUE
J 0
(-2230 1595);
DISPLAY 2.276596 (-2230 1595);
PAINT GREEN (-2230 1595);
DISPLAY INVISIBLE (-2230 1595);
FORCEADD TAP..7
(-2750 1725);
FORCEPROP 3 LASTPIN (-2750 1775) SIG_NAME P3E_CPU0_PE1_PCH_C_TXN<15>
J 0
(-2740 1785);
DISPLAY 0.659574 (-2740 1785);
PAINT MONO (-2740 1785);
DISPLAY INVISIBLE (-2740 1785);
FORCEPROP 1 LASTPIN (-2750 1775) BN 15
R 1
J 0
(-2757 1723);
DISPLAY 0.617021 (-2757 1723);
PAINT GREEN (-2757 1723);
FORCEPROP 1 LAST PATH I158
J 0
(-2752 1725);
DISPLAY 0.872340 (-2752 1725);
PAINT GREEN (-2752 1725);
DISPLAY INVISIBLE (-2752 1725);
FORCEPROP 2 LAST CDS_LIB mstr_standard
J 0
(-2750 1725);
PAINT ORANGE (-2750 1725);
DISPLAY INVISIBLE (-2750 1725);
FORCEPROP 1 LAST BODY_TYPE PLUMBING
J 0
(-2700 1725);
DISPLAY 2.276596 (-2700 1725);
PAINT GREEN (-2700 1725);
DISPLAY INVISIBLE (-2700 1725);
FORCEPROP 1 LAST HDL_TAP TRUE
J 0
(-2430 1595);
DISPLAY 2.276596 (-2430 1595);
PAINT GREEN (-2430 1595);
DISPLAY INVISIBLE (-2430 1595);
FORCEADD TAP..3
(-1350 2525);
FORCEPROP 3 LASTPIN (-1350 2475) SIG_NAME P3E_CPU0_PE1_PCH_TXN<8>
J 0
(-1340 2485);
DISPLAY 0.659574 (-1340 2485);
PAINT MONO (-1340 2485);
DISPLAY INVISIBLE (-1340 2485);
FORCEPROP 1 LASTPIN (-1350 2475) BN 8
R 1
J 0
(-1357 2463);
DISPLAY 0.617021 (-1357 2463);
PAINT GREEN (-1357 2463);
FORCEPROP 1 LAST PATH I159
J 0
(-1352 2525);
DISPLAY 0.872340 (-1352 2525);
PAINT GREEN (-1352 2525);
DISPLAY INVISIBLE (-1352 2525);
FORCEPROP 2 LAST CDS_LIB mstr_standard
J 0
(-1350 2525);
PAINT ORANGE (-1350 2525);
DISPLAY INVISIBLE (-1350 2525);
FORCEPROP 1 LAST BODY_TYPE PLUMBING
J 0
(-1300 2475);
DISPLAY 2.276596 (-1300 2475);
PAINT GREEN (-1300 2475);
DISPLAY INVISIBLE (-1300 2475);
FORCEPROP 1 LAST HDL_TAP TRUE
J 0
(-1030 2395);
DISPLAY 2.276596 (-1030 2395);
PAINT GREEN (-1030 2395);
DISPLAY INVISIBLE (-1030 2395);
FORCEADD TAP..3
(-500 3900);
FORCEPROP 3 LASTPIN (-500 3850) SIG_NAME P3E_CPU0_PE2_SS_TXN<14>
J 0
(-490 3860);
DISPLAY 0.659574 (-490 3860);
PAINT MONO (-490 3860);
DISPLAY INVISIBLE (-490 3860);
FORCEPROP 1 LASTPIN (-500 3850) BN 14
R 1
J 0
(-507 3838);
DISPLAY 0.617021 (-507 3838);
PAINT GREEN (-507 3838);
FORCEPROP 1 LAST PATH I16
J 0
(-502 3900);
DISPLAY 0.872340 (-502 3900);
PAINT GREEN (-502 3900);
DISPLAY INVISIBLE (-502 3900);
FORCEPROP 2 LAST CDS_LIB mstr_standard
J 0
(-500 3900);
PAINT ORANGE (-500 3900);
DISPLAY INVISIBLE (-500 3900);
FORCEPROP 1 LAST BODY_TYPE PLUMBING
J 0
(-450 3850);
DISPLAY 2.276596 (-450 3850);
PAINT GREEN (-450 3850);
DISPLAY INVISIBLE (-450 3850);
FORCEPROP 1 LAST HDL_TAP TRUE
J 0
(-180 3770);
DISPLAY 2.276596 (-180 3770);
PAINT GREEN (-180 3770);
DISPLAY INVISIBLE (-180 3770);
FORCEADD CAP..1
R 2
(-1350 2275);
FORCEPROP 0 LAST GROUP PCIE_UPLINK
J 0
(-1525 2425);
DISPLAY 0.638298 (-1525 2425);
PAINT BROWN (-1525 2425);
DISPLAY BOTH (-1525 2425);
FORCEPROP 1 LASTPIN (-1350 2175) $PN 2
J 2
(-1360 2155);
DISPLAY 0.617021 (-1360 2155);
PAINT ORANGE (-1360 2155);
FORCEPROP 1 LASTPIN (-1350 2375) $PN 1
J 2
(-1360 2355);
DISPLAY 0.617021 (-1360 2355);
PAINT ORANGE (-1360 2355);
FORCEPROP 1 LAST MATERIAL X7R
J 2
(-1400 2175);
DISPLAY 0.617021 (-1400 2175);
PAINT SKYBLUE (-1400 2175);
FORCEPROP 1 LAST VOLTAGE 16V
J 2
(-1400 2275);
DISPLAY 0.617021 (-1400 2275);
PAINT SKYBLUE (-1400 2275);
FORCEPROP 1 LAST TOLERANCE 10%
J 2
(-1400 2225);
DISPLAY 0.617021 (-1400 2225);
PAINT SKYBLUE (-1400 2225);
FORCEPROP 1 LAST VALUE 0.22UF
J 2
(-1400 2325);
DISPLAY 0.617021 (-1400 2325);
PAINT SKYBLUE (-1400 2325);
FORCEPROP 1 LAST LOCATION C6B19
J 2
(-1400 2375);
DISPLAY 0.617021 (-1400 2375);
PAINT AQUA (-1400 2375);
FORCEPROP 1 LAST PART_NUMBER A36096-155
J 2
(-1400 2125);
DISPLAY 0.617021 (-1400 2125);
PAINT BLUE (-1400 2125);
FORCEPROP 1 LAST PACK_TYPE 0402
J 2
(-1400 2075);
DISPLAY 0.617021 (-1400 2075);
PAINT SKYBLUE (-1400 2075);
FORCEPROP 2 LAST ROOM OCP_STEERING
J 2
(-1350 2275);
PAINT MONO (-1350 2275);
DISPLAY INVISIBLE (-1350 2275);
FORCEPROP 1 LAST PATH I160
J 2
(-1400 2425);
DISPLAY 0.978723 (-1400 2425);
PAINT WHITE (-1400 2425);
DISPLAY INVISIBLE (-1400 2425);
FORCEPROP 2 LAST CDS_LOCATION C6B19
J 2
(-1400 2375);
DISPLAY 0.617021 (-1400 2375);
PAINT AQUA (-1400 2375);
DISPLAY INVISIBLE (-1400 2375);
FORCEPROP 2 LAST SEC 1
J 0
(-1400 2475);
DISPLAY 0.680851 (-1400 2475);
PAINT MONO (-1400 2475);
DISPLAY INVISIBLE (-1400 2475);
FORCEPROP 2 LAST CDS_LIB mstr_discrete
J 0
(-1350 2275);
PAINT ORANGE (-1350 2275);
DISPLAY INVISIBLE (-1350 2275);
FORCEPROP 2 LAST SEC_TYPE 0402
J 0
(-1400 2475);
DISPLAY 1.021277 (-1400 2475);
PAINT ORANGE (-1400 2475);
DISPLAY INVISIBLE (-1400 2475);
FORCEADD TAP..3
(-1550 2525);
FORCEPROP 3 LASTPIN (-1550 2475) SIG_NAME P3E_CPU0_PE1_PCH_TXN<9>
J 0
(-1540 2485);
DISPLAY 0.659574 (-1540 2485);
PAINT MONO (-1540 2485);
DISPLAY INVISIBLE (-1540 2485);
FORCEPROP 1 LASTPIN (-1550 2475) BN 9
R 1
J 0
(-1557 2463);
DISPLAY 0.617021 (-1557 2463);
PAINT GREEN (-1557 2463);
FORCEPROP 1 LAST PATH I161
J 0
(-1552 2525);
DISPLAY 0.872340 (-1552 2525);
PAINT GREEN (-1552 2525);
DISPLAY INVISIBLE (-1552 2525);
FORCEPROP 2 LAST CDS_LIB mstr_standard
J 0
(-1550 2525);
PAINT ORANGE (-1550 2525);
DISPLAY INVISIBLE (-1550 2525);
FORCEPROP 1 LAST BODY_TYPE PLUMBING
J 0
(-1500 2475);
DISPLAY 2.276596 (-1500 2475);
PAINT GREEN (-1500 2475);
DISPLAY INVISIBLE (-1500 2475);
FORCEPROP 1 LAST HDL_TAP TRUE
J 0
(-1230 2395);
DISPLAY 2.276596 (-1230 2395);
PAINT GREEN (-1230 2395);
DISPLAY INVISIBLE (-1230 2395);
FORCEADD TAP..3
(-1750 2525);
FORCEPROP 3 LASTPIN (-1750 2475) SIG_NAME P3E_CPU0_PE1_PCH_TXN<10>
J 0
(-1740 2485);
DISPLAY 0.659574 (-1740 2485);
PAINT MONO (-1740 2485);
DISPLAY INVISIBLE (-1740 2485);
FORCEPROP 1 LASTPIN (-1750 2475) BN 10
R 1
J 0
(-1757 2463);
DISPLAY 0.617021 (-1757 2463);
PAINT GREEN (-1757 2463);
FORCEPROP 1 LAST PATH I162
J 0
(-1752 2525);
DISPLAY 0.872340 (-1752 2525);
PAINT GREEN (-1752 2525);
DISPLAY INVISIBLE (-1752 2525);
FORCEPROP 2 LAST CDS_LIB mstr_standard
J 0
(-1750 2525);
PAINT ORANGE (-1750 2525);
DISPLAY INVISIBLE (-1750 2525);
FORCEPROP 1 LAST BODY_TYPE PLUMBING
J 0
(-1700 2475);
DISPLAY 2.276596 (-1700 2475);
PAINT GREEN (-1700 2475);
DISPLAY INVISIBLE (-1700 2475);
FORCEPROP 1 LAST HDL_TAP TRUE
J 0
(-1430 2395);
DISPLAY 2.276596 (-1430 2395);
PAINT GREEN (-1430 2395);
DISPLAY INVISIBLE (-1430 2395);
FORCEADD CAP..1
R 2
(-1750 2275);
FORCEPROP 1 LAST PART_NUMBER A36096-155
J 2
(-1800 2125);
DISPLAY 0.617021 (-1800 2125);
PAINT BLUE (-1800 2125);
FORCEPROP 1 LASTPIN (-1750 2375) $PN 1
J 2
(-1760 2355);
DISPLAY 0.617021 (-1760 2355);
PAINT ORANGE (-1760 2355);
FORCEPROP 1 LASTPIN (-1750 2175) $PN 2
J 2
(-1760 2155);
DISPLAY 0.617021 (-1760 2155);
PAINT ORANGE (-1760 2155);
FORCEPROP 1 LAST MATERIAL X7R
J 2
(-1800 2175);
DISPLAY 0.617021 (-1800 2175);
PAINT SKYBLUE (-1800 2175);
FORCEPROP 1 LAST VALUE 0.22UF
J 2
(-1800 2325);
DISPLAY 0.617021 (-1800 2325);
PAINT SKYBLUE (-1800 2325);
FORCEPROP 1 LAST LOCATION C6B15
J 2
(-1800 2375);
DISPLAY 0.617021 (-1800 2375);
PAINT AQUA (-1800 2375);
FORCEPROP 1 LAST PACK_TYPE 0402
J 2
(-1800 2075);
DISPLAY 0.617021 (-1800 2075);
PAINT SKYBLUE (-1800 2075);
FORCEPROP 1 LAST TOLERANCE 10%
J 2
(-1800 2225);
DISPLAY 0.617021 (-1800 2225);
PAINT SKYBLUE (-1800 2225);
FORCEPROP 1 LAST VOLTAGE 16V
J 2
(-1800 2275);
DISPLAY 0.617021 (-1800 2275);
PAINT SKYBLUE (-1800 2275);
FORCEPROP 0 LAST GROUP PCIE_UPLINK
J 0
(-1925 2425);
DISPLAY 0.638298 (-1925 2425);
PAINT BROWN (-1925 2425);
DISPLAY BOTH (-1925 2425);
FORCEPROP 2 LAST ROOM OCP_STEERING
J 2
(-1750 2275);
PAINT MONO (-1750 2275);
DISPLAY INVISIBLE (-1750 2275);
FORCEPROP 1 LAST PATH I163
J 2
(-1800 2425);
DISPLAY 0.978723 (-1800 2425);
PAINT WHITE (-1800 2425);
DISPLAY INVISIBLE (-1800 2425);
FORCEPROP 2 LAST CDS_LOCATION C6B15
J 2
(-1800 2375);
DISPLAY 0.617021 (-1800 2375);
PAINT AQUA (-1800 2375);
DISPLAY INVISIBLE (-1800 2375);
FORCEPROP 2 LAST SEC 1
J 0
(-1800 2475);
DISPLAY 0.680851 (-1800 2475);
PAINT MONO (-1800 2475);
DISPLAY INVISIBLE (-1800 2475);
FORCEPROP 2 LAST CDS_LIB mstr_discrete
J 0
(-1750 2275);
PAINT ORANGE (-1750 2275);
DISPLAY INVISIBLE (-1750 2275);
FORCEPROP 2 LAST SEC_TYPE 0402
J 0
(-1800 2475);
DISPLAY 1.021277 (-1800 2475);
PAINT ORANGE (-1800 2475);
DISPLAY INVISIBLE (-1800 2475);
FORCEADD TAP..3
(-2150 2525);
FORCEPROP 3 LASTPIN (-2150 2475) SIG_NAME P3E_CPU0_PE1_PCH_TXN<12>
J 0
(-2140 2485);
DISPLAY 0.659574 (-2140 2485);
PAINT MONO (-2140 2485);
DISPLAY INVISIBLE (-2140 2485);
FORCEPROP 1 LASTPIN (-2150 2475) BN 12
R 1
J 0
(-2157 2463);
DISPLAY 0.617021 (-2157 2463);
PAINT GREEN (-2157 2463);
FORCEPROP 1 LAST PATH I164
J 0
(-2152 2525);
DISPLAY 0.872340 (-2152 2525);
PAINT GREEN (-2152 2525);
DISPLAY INVISIBLE (-2152 2525);
FORCEPROP 2 LAST CDS_LIB mstr_standard
J 0
(-2150 2525);
PAINT ORANGE (-2150 2525);
DISPLAY INVISIBLE (-2150 2525);
FORCEPROP 1 LAST BODY_TYPE PLUMBING
J 0
(-2100 2475);
DISPLAY 2.276596 (-2100 2475);
PAINT GREEN (-2100 2475);
DISPLAY INVISIBLE (-2100 2475);
FORCEPROP 1 LAST HDL_TAP TRUE
J 0
(-1830 2395);
DISPLAY 2.276596 (-1830 2395);
PAINT GREEN (-1830 2395);
DISPLAY INVISIBLE (-1830 2395);
FORCEADD TAP..3
(-1950 2525);
FORCEPROP 3 LASTPIN (-1950 2475) SIG_NAME P3E_CPU0_PE1_PCH_TXN<11>
J 0
(-1940 2485);
DISPLAY 0.659574 (-1940 2485);
PAINT MONO (-1940 2485);
DISPLAY INVISIBLE (-1940 2485);
FORCEPROP 1 LASTPIN (-1950 2475) BN 11
R 1
J 0
(-1957 2463);
DISPLAY 0.617021 (-1957 2463);
PAINT GREEN (-1957 2463);
FORCEPROP 1 LAST PATH I165
J 0
(-1952 2525);
DISPLAY 0.872340 (-1952 2525);
PAINT GREEN (-1952 2525);
DISPLAY INVISIBLE (-1952 2525);
FORCEPROP 2 LAST CDS_LIB mstr_standard
J 0
(-1950 2525);
PAINT ORANGE (-1950 2525);
DISPLAY INVISIBLE (-1950 2525);
FORCEPROP 1 LAST BODY_TYPE PLUMBING
J 0
(-1900 2475);
DISPLAY 2.276596 (-1900 2475);
PAINT GREEN (-1900 2475);
DISPLAY INVISIBLE (-1900 2475);
FORCEPROP 1 LAST HDL_TAP TRUE
J 0
(-1630 2395);
DISPLAY 2.276596 (-1630 2395);
PAINT GREEN (-1630 2395);
DISPLAY INVISIBLE (-1630 2395);
FORCEADD CAP..1
R 2
(-2150 2275);
FORCEPROP 1 LAST PACK_TYPE 0402
J 2
(-2200 2075);
DISPLAY 0.617021 (-2200 2075);
PAINT SKYBLUE (-2200 2075);
FORCEPROP 1 LAST PART_NUMBER A36096-155
J 2
(-2200 2125);
DISPLAY 0.617021 (-2200 2125);
PAINT BLUE (-2200 2125);
FORCEPROP 1 LAST MATERIAL X7R
J 2
(-2200 2175);
DISPLAY 0.617021 (-2200 2175);
PAINT SKYBLUE (-2200 2175);
FORCEPROP 1 LAST TOLERANCE 10%
J 2
(-2200 2225);
DISPLAY 0.617021 (-2200 2225);
PAINT SKYBLUE (-2200 2225);
FORCEPROP 1 LASTPIN (-2150 2375) $PN 1
J 2
(-2160 2355);
DISPLAY 0.617021 (-2160 2355);
PAINT ORANGE (-2160 2355);
FORCEPROP 1 LAST VOLTAGE 16V
J 2
(-2200 2275);
DISPLAY 0.617021 (-2200 2275);
PAINT SKYBLUE (-2200 2275);
FORCEPROP 1 LAST VALUE 0.22UF
J 2
(-2200 2325);
DISPLAY 0.617021 (-2200 2325);
PAINT SKYBLUE (-2200 2325);
FORCEPROP 1 LAST LOCATION C6B11
J 2
(-2200 2375);
DISPLAY 0.617021 (-2200 2375);
PAINT AQUA (-2200 2375);
FORCEPROP 1 LASTPIN (-2150 2175) $PN 2
J 2
(-2160 2155);
DISPLAY 0.617021 (-2160 2155);
PAINT ORANGE (-2160 2155);
FORCEPROP 0 LAST GROUP PCIE_UPLINK
J 0
(-2325 2425);
DISPLAY 0.638298 (-2325 2425);
PAINT BROWN (-2325 2425);
DISPLAY BOTH (-2325 2425);
FORCEPROP 2 LAST ROOM OCP_STEERING
J 2
(-2150 2275);
PAINT MONO (-2150 2275);
DISPLAY INVISIBLE (-2150 2275);
FORCEPROP 1 LAST PATH I166
J 2
(-2200 2425);
DISPLAY 0.978723 (-2200 2425);
PAINT WHITE (-2200 2425);
DISPLAY INVISIBLE (-2200 2425);
FORCEPROP 2 LAST CDS_LOCATION C6B11
J 2
(-2200 2375);
DISPLAY 0.617021 (-2200 2375);
PAINT AQUA (-2200 2375);
DISPLAY INVISIBLE (-2200 2375);
FORCEPROP 2 LAST SEC 1
J 0
(-2200 2475);
DISPLAY 0.680851 (-2200 2475);
PAINT MONO (-2200 2475);
DISPLAY INVISIBLE (-2200 2475);
FORCEPROP 2 LAST CDS_LIB mstr_discrete
J 0
(-2150 2275);
PAINT ORANGE (-2150 2275);
DISPLAY INVISIBLE (-2150 2275);
FORCEPROP 2 LAST SEC_TYPE 0402
J 0
(-2200 2475);
DISPLAY 1.021277 (-2200 2475);
PAINT ORANGE (-2200 2475);
DISPLAY INVISIBLE (-2200 2475);
FORCEADD TAP..3
(-2350 2525);
FORCEPROP 3 LASTPIN (-2350 2475) SIG_NAME P3E_CPU0_PE1_PCH_TXN<13>
J 0
(-2340 2485);
DISPLAY 0.659574 (-2340 2485);
PAINT MONO (-2340 2485);
DISPLAY INVISIBLE (-2340 2485);
FORCEPROP 1 LASTPIN (-2350 2475) BN 13
R 1
J 0
(-2357 2463);
DISPLAY 0.617021 (-2357 2463);
PAINT GREEN (-2357 2463);
FORCEPROP 1 LAST PATH I167
J 0
(-2352 2525);
DISPLAY 0.872340 (-2352 2525);
PAINT GREEN (-2352 2525);
DISPLAY INVISIBLE (-2352 2525);
FORCEPROP 2 LAST CDS_LIB mstr_standard
J 0
(-2350 2525);
PAINT ORANGE (-2350 2525);
DISPLAY INVISIBLE (-2350 2525);
FORCEPROP 1 LAST BODY_TYPE PLUMBING
J 0
(-2300 2475);
DISPLAY 2.276596 (-2300 2475);
PAINT GREEN (-2300 2475);
DISPLAY INVISIBLE (-2300 2475);
FORCEPROP 1 LAST HDL_TAP TRUE
J 0
(-2030 2395);
DISPLAY 2.276596 (-2030 2395);
PAINT GREEN (-2030 2395);
DISPLAY INVISIBLE (-2030 2395);
FORCEADD TAP..3
(-2550 2525);
FORCEPROP 3 LASTPIN (-2550 2475) SIG_NAME P3E_CPU0_PE1_PCH_TXN<14>
J 0
(-2540 2485);
DISPLAY 0.659574 (-2540 2485);
PAINT MONO (-2540 2485);
DISPLAY INVISIBLE (-2540 2485);
FORCEPROP 1 LASTPIN (-2550 2475) BN 14
R 1
J 0
(-2557 2463);
DISPLAY 0.617021 (-2557 2463);
PAINT GREEN (-2557 2463);
FORCEPROP 1 LAST PATH I168
J 0
(-2552 2525);
DISPLAY 0.872340 (-2552 2525);
PAINT GREEN (-2552 2525);
DISPLAY INVISIBLE (-2552 2525);
FORCEPROP 2 LAST CDS_LIB mstr_standard
J 0
(-2550 2525);
PAINT ORANGE (-2550 2525);
DISPLAY INVISIBLE (-2550 2525);
FORCEPROP 1 LAST BODY_TYPE PLUMBING
J 0
(-2500 2475);
DISPLAY 2.276596 (-2500 2475);
PAINT GREEN (-2500 2475);
DISPLAY INVISIBLE (-2500 2475);
FORCEPROP 1 LAST HDL_TAP TRUE
J 0
(-2230 2395);
DISPLAY 2.276596 (-2230 2395);
PAINT GREEN (-2230 2395);
DISPLAY INVISIBLE (-2230 2395);
FORCEADD CAP..1
R 2
(-2550 2275);
FORCEPROP 1 LAST VOLTAGE 16V
J 2
(-2600 2275);
DISPLAY 0.617021 (-2600 2275);
PAINT SKYBLUE (-2600 2275);
FORCEPROP 1 LASTPIN (-2550 2375) $PN 1
J 2
(-2560 2355);
DISPLAY 0.617021 (-2560 2355);
PAINT ORANGE (-2560 2355);
FORCEPROP 1 LASTPIN (-2550 2175) $PN 2
J 2
(-2560 2155);
DISPLAY 0.617021 (-2560 2155);
PAINT ORANGE (-2560 2155);
FORCEPROP 1 LAST MATERIAL X7R
J 2
(-2600 2175);
DISPLAY 0.617021 (-2600 2175);
PAINT SKYBLUE (-2600 2175);
FORCEPROP 1 LAST PACK_TYPE 0402
J 2
(-2600 2075);
DISPLAY 0.617021 (-2600 2075);
PAINT SKYBLUE (-2600 2075);
FORCEPROP 1 LAST TOLERANCE 10%
J 2
(-2600 2225);
DISPLAY 0.617021 (-2600 2225);
PAINT SKYBLUE (-2600 2225);
FORCEPROP 1 LAST VALUE 0.22UF
J 2
(-2600 2325);
DISPLAY 0.617021 (-2600 2325);
PAINT SKYBLUE (-2600 2325);
FORCEPROP 1 LAST PART_NUMBER A36096-155
J 2
(-2600 2125);
DISPLAY 0.617021 (-2600 2125);
PAINT BLUE (-2600 2125);
FORCEPROP 1 LAST LOCATION C6B6
J 2
(-2600 2375);
DISPLAY 0.617021 (-2600 2375);
PAINT AQUA (-2600 2375);
FORCEPROP 0 LAST GROUP PCIE_UPLINK
J 0
(-2725 2425);
DISPLAY 0.638298 (-2725 2425);
PAINT BROWN (-2725 2425);
DISPLAY BOTH (-2725 2425);
FORCEPROP 2 LAST ROOM OCP_STEERING
J 2
(-2550 2275);
PAINT MONO (-2550 2275);
DISPLAY INVISIBLE (-2550 2275);
FORCEPROP 1 LAST PATH I169
J 2
(-2600 2425);
DISPLAY 0.978723 (-2600 2425);
PAINT WHITE (-2600 2425);
DISPLAY INVISIBLE (-2600 2425);
FORCEPROP 2 LAST CDS_LOCATION C6B6
J 2
(-2600 2375);
DISPLAY 0.617021 (-2600 2375);
PAINT AQUA (-2600 2375);
DISPLAY INVISIBLE (-2600 2375);
FORCEPROP 2 LAST SEC 1
J 0
(-2600 2475);
DISPLAY 0.680851 (-2600 2475);
PAINT MONO (-2600 2475);
DISPLAY INVISIBLE (-2600 2475);
FORCEPROP 2 LAST CDS_LIB mstr_discrete
J 0
(-2550 2275);
PAINT ORANGE (-2550 2275);
DISPLAY INVISIBLE (-2550 2275);
FORCEPROP 2 LAST SEC_TYPE 0402
J 0
(-2600 2475);
DISPLAY 1.021277 (-2600 2475);
PAINT ORANGE (-2600 2475);
DISPLAY INVISIBLE (-2600 2475);
FORCEADD TAP..7
(-550 4100);
FORCEPROP 3 LASTPIN (-550 4150) SIG_NAME P3E_CPU0_PE2_SS_C_TXP<14>
J 0
(-540 4160);
DISPLAY 0.659574 (-540 4160);
PAINT MONO (-540 4160);
DISPLAY INVISIBLE (-540 4160);
FORCEPROP 1 LASTPIN (-550 4150) BN 14
R 1
J 0
(-557 4098);
DISPLAY 0.617021 (-557 4098);
PAINT GREEN (-557 4098);
FORCEPROP 1 LAST PATH I17
J 0
(-552 4100);
DISPLAY 0.872340 (-552 4100);
PAINT GREEN (-552 4100);
DISPLAY INVISIBLE (-552 4100);
FORCEPROP 2 LAST CDS_LIB mstr_standard
J 0
(-550 4100);
PAINT ORANGE (-550 4100);
DISPLAY INVISIBLE (-550 4100);
FORCEPROP 1 LAST BODY_TYPE PLUMBING
J 0
(-500 4100);
DISPLAY 2.276596 (-500 4100);
PAINT GREEN (-500 4100);
DISPLAY INVISIBLE (-500 4100);
FORCEPROP 1 LAST HDL_TAP TRUE
J 0
(-230 3970);
DISPLAY 2.276596 (-230 3970);
PAINT GREEN (-230 3970);
DISPLAY INVISIBLE (-230 3970);
FORCEADD TAP..3
(-2750 2525);
FORCEPROP 3 LASTPIN (-2750 2475) SIG_NAME P3E_CPU0_PE1_PCH_TXN<15>
J 0
(-2740 2485);
DISPLAY 0.659574 (-2740 2485);
PAINT MONO (-2740 2485);
DISPLAY INVISIBLE (-2740 2485);
FORCEPROP 1 LASTPIN (-2750 2475) BN 15
R 1
J 0
(-2757 2463);
DISPLAY 0.617021 (-2757 2463);
PAINT GREEN (-2757 2463);
FORCEPROP 1 LAST PATH I170
J 0
(-2752 2525);
DISPLAY 0.872340 (-2752 2525);
PAINT GREEN (-2752 2525);
DISPLAY INVISIBLE (-2752 2525);
FORCEPROP 2 LAST CDS_LIB mstr_standard
J 0
(-2750 2525);
PAINT ORANGE (-2750 2525);
DISPLAY INVISIBLE (-2750 2525);
FORCEPROP 1 LAST BODY_TYPE PLUMBING
J 0
(-2700 2475);
DISPLAY 2.276596 (-2700 2475);
PAINT GREEN (-2700 2475);
DISPLAY INVISIBLE (-2700 2475);
FORCEPROP 1 LAST HDL_TAP TRUE
J 0
(-2430 2395);
DISPLAY 2.276596 (-2430 2395);
PAINT GREEN (-2430 2395);
DISPLAY INVISIBLE (-2430 2395);
FORCEADD OFFPAGE..1
(-2925 2575);
FORCEPROP 2 LAST $XR1 244 
J 0
(-3296 2575);
DISPLAY 0.638298 (-3296 2575);
PAINT MONO (-3296 2575);
FORCEPROP 2 LAST $XR0 30 
J 0
(-3176 2575);
DISPLAY 0.638298 (-3176 2575);
PAINT MONO (-3176 2575);
FORCEPROP 2 LAST PATH I171
J 0
(-2875 2650);
DISPLAY 1.021277 (-2875 2650);
PAINT ORANGE (-2875 2650);
DISPLAY INVISIBLE (-2875 2650);
FORCEPROP 2 LAST CDS_LIB mstr_standard
J 0
(-2925 2575);
PAINT ORANGE (-2925 2575);
DISPLAY INVISIBLE (-2925 2575);
FORCEPROP 1 LAST OFFPAGE TRUE
J 0
(-2605 2445);
PAINT GREEN (-2605 2445);
DISPLAY INVISIBLE (-2605 2445);
FORCEPROP 1 LAST COMMENT_BODY TRUE
J 0
(-2805 2475);
DISPLAY 2.276596 (-2805 2475);
PAINT GREEN (-2805 2475);
DISPLAY INVISIBLE (-2805 2475);
FORCEADD TAP..3
(-1300 1525);
FORCEPROP 3 LASTPIN (-1300 1475) SIG_NAME P3E_CPU0_PE1_PCH_TXP<8>
J 0
(-1290 1485);
DISPLAY 0.659574 (-1290 1485);
PAINT MONO (-1290 1485);
DISPLAY INVISIBLE (-1290 1485);
FORCEPROP 1 LASTPIN (-1300 1475) BN 8
R 1
J 0
(-1307 1463);
DISPLAY 0.617021 (-1307 1463);
PAINT GREEN (-1307 1463);
FORCEPROP 1 LAST PATH I172
J 0
(-1302 1525);
DISPLAY 0.872340 (-1302 1525);
PAINT GREEN (-1302 1525);
DISPLAY INVISIBLE (-1302 1525);
FORCEPROP 2 LAST CDS_LIB mstr_standard
J 0
(-1300 1525);
PAINT ORANGE (-1300 1525);
DISPLAY INVISIBLE (-1300 1525);
FORCEPROP 1 LAST BODY_TYPE PLUMBING
J 0
(-1250 1475);
DISPLAY 2.276596 (-1250 1475);
PAINT GREEN (-1250 1475);
DISPLAY INVISIBLE (-1250 1475);
FORCEPROP 1 LAST HDL_TAP TRUE
J 0
(-980 1395);
DISPLAY 2.276596 (-980 1395);
PAINT GREEN (-980 1395);
DISPLAY INVISIBLE (-980 1395);
FORCEADD CAP..1
R 2
(-1300 1275);
FORCEPROP 0 LAST GROUP PCIE_UPLINK
J 0
(-1450 1425);
DISPLAY 0.638298 (-1450 1425);
PAINT BROWN (-1450 1425);
DISPLAY BOTH (-1450 1425);
FORCEPROP 1 LAST TOLERANCE 10%
J 2
(-1350 1225);
DISPLAY 0.617021 (-1350 1225);
PAINT SKYBLUE (-1350 1225);
FORCEPROP 1 LASTPIN (-1300 1375) $PN 1
J 2
(-1310 1355);
DISPLAY 0.617021 (-1310 1355);
PAINT ORANGE (-1310 1355);
FORCEPROP 1 LASTPIN (-1300 1175) $PN 2
J 2
(-1310 1155);
DISPLAY 0.617021 (-1310 1155);
PAINT ORANGE (-1310 1155);
FORCEPROP 1 LAST MATERIAL X7R
J 2
(-1350 1175);
DISPLAY 0.617021 (-1350 1175);
PAINT SKYBLUE (-1350 1175);
FORCEPROP 1 LAST PACK_TYPE 0402
J 2
(-1350 1075);
DISPLAY 0.617021 (-1350 1075);
PAINT SKYBLUE (-1350 1075);
FORCEPROP 1 LAST PART_NUMBER A36096-155
J 2
(-1350 1125);
DISPLAY 0.617021 (-1350 1125);
PAINT BLUE (-1350 1125);
FORCEPROP 1 LAST VALUE 0.22UF
J 2
(-1350 1325);
DISPLAY 0.617021 (-1350 1325);
PAINT SKYBLUE (-1350 1325);
FORCEPROP 1 LAST VOLTAGE 16V
J 2
(-1350 1275);
DISPLAY 0.617021 (-1350 1275);
PAINT SKYBLUE (-1350 1275);
FORCEPROP 1 LAST LOCATION C6B20
J 2
(-1350 1375);
DISPLAY 0.617021 (-1350 1375);
PAINT AQUA (-1350 1375);
FORCEPROP 2 LAST ROOM OCP_STEERING
J 2
(-1300 1275);
PAINT MONO (-1300 1275);
DISPLAY INVISIBLE (-1300 1275);
FORCEPROP 1 LAST PATH I173
J 2
(-1350 1425);
DISPLAY 0.978723 (-1350 1425);
PAINT WHITE (-1350 1425);
DISPLAY INVISIBLE (-1350 1425);
FORCEPROP 2 LAST CDS_LOCATION C6B20
J 2
(-1350 1375);
DISPLAY 0.617021 (-1350 1375);
PAINT AQUA (-1350 1375);
DISPLAY INVISIBLE (-1350 1375);
FORCEPROP 2 LAST SEC 1
J 0
(-1350 1475);
DISPLAY 0.680851 (-1350 1475);
PAINT MONO (-1350 1475);
DISPLAY INVISIBLE (-1350 1475);
FORCEPROP 2 LAST CDS_LIB mstr_discrete
J 0
(-1300 1275);
PAINT ORANGE (-1300 1275);
DISPLAY INVISIBLE (-1300 1275);
FORCEPROP 2 LAST SEC_TYPE 0402
J 0
(-1350 1475);
DISPLAY 1.021277 (-1350 1475);
PAINT ORANGE (-1350 1475);
DISPLAY INVISIBLE (-1350 1475);
FORCEADD TAP..7
(-1300 725);
FORCEPROP 3 LASTPIN (-1300 775) SIG_NAME P3E_CPU0_PE1_PCH_C_TXP<8>
J 0
(-1290 785);
DISPLAY 0.659574 (-1290 785);
PAINT MONO (-1290 785);
DISPLAY INVISIBLE (-1290 785);
FORCEPROP 1 LASTPIN (-1300 775) BN 8
R 1
J 0
(-1307 723);
DISPLAY 0.617021 (-1307 723);
PAINT GREEN (-1307 723);
FORCEPROP 1 LAST PATH I174
J 0
(-1302 725);
DISPLAY 0.872340 (-1302 725);
PAINT GREEN (-1302 725);
DISPLAY INVISIBLE (-1302 725);
FORCEPROP 2 LAST CDS_LIB mstr_standard
J 0
(-1300 725);
PAINT ORANGE (-1300 725);
DISPLAY INVISIBLE (-1300 725);
FORCEPROP 1 LAST BODY_TYPE PLUMBING
J 0
(-1250 725);
DISPLAY 2.276596 (-1250 725);
PAINT GREEN (-1250 725);
DISPLAY INVISIBLE (-1250 725);
FORCEPROP 1 LAST HDL_TAP TRUE
J 0
(-980 595);
DISPLAY 2.276596 (-980 595);
PAINT GREEN (-980 595);
DISPLAY INVISIBLE (-980 595);
FORCEADD CAP..1
R 2
(-1550 1975);
FORCEPROP 0 LAST GROUP PCIE_UPLINK
J 0
(-1700 1700);
DISPLAY 0.638298 (-1700 1700);
PAINT BROWN (-1700 1700);
DISPLAY BOTH (-1700 1700);
FORCEPROP 1 LAST PART_NUMBER A36096-155
J 2
(-1600 1825);
DISPLAY 0.617021 (-1600 1825);
PAINT BLUE (-1600 1825);
FORCEPROP 1 LASTPIN (-1550 2075) $PN 1
J 2
(-1560 2055);
DISPLAY 0.617021 (-1560 2055);
PAINT ORANGE (-1560 2055);
FORCEPROP 1 LASTPIN (-1550 1875) $PN 2
J 2
(-1560 1855);
DISPLAY 0.617021 (-1560 1855);
PAINT ORANGE (-1560 1855);
FORCEPROP 1 LAST MATERIAL X7R
J 2
(-1600 1875);
DISPLAY 0.617021 (-1600 1875);
PAINT SKYBLUE (-1600 1875);
FORCEPROP 1 LAST LOCATION C6B17
J 2
(-1600 2075);
DISPLAY 0.617021 (-1600 2075);
PAINT AQUA (-1600 2075);
FORCEPROP 1 LAST TOLERANCE 10%
J 2
(-1600 1925);
DISPLAY 0.617021 (-1600 1925);
PAINT SKYBLUE (-1600 1925);
FORCEPROP 1 LAST VOLTAGE 16V
J 2
(-1600 1975);
DISPLAY 0.617021 (-1600 1975);
PAINT SKYBLUE (-1600 1975);
FORCEPROP 1 LAST VALUE 0.22UF
J 2
(-1600 2025);
DISPLAY 0.617021 (-1600 2025);
PAINT SKYBLUE (-1600 2025);
FORCEPROP 1 LAST PACK_TYPE 0402
J 2
(-1600 1775);
DISPLAY 0.617021 (-1600 1775);
PAINT SKYBLUE (-1600 1775);
FORCEPROP 2 LAST ROOM OCP_STEERING
J 2
(-1550 1975);
PAINT MONO (-1550 1975);
DISPLAY INVISIBLE (-1550 1975);
FORCEPROP 1 LAST PATH I175
J 2
(-1600 2125);
DISPLAY 0.978723 (-1600 2125);
PAINT WHITE (-1600 2125);
DISPLAY INVISIBLE (-1600 2125);
FORCEPROP 2 LAST CDS_LOCATION C6B17
J 2
(-1600 2075);
DISPLAY 0.617021 (-1600 2075);
PAINT AQUA (-1600 2075);
DISPLAY INVISIBLE (-1600 2075);
FORCEPROP 2 LAST SEC 1
J 0
(-1600 2175);
DISPLAY 0.680851 (-1600 2175);
PAINT MONO (-1600 2175);
DISPLAY INVISIBLE (-1600 2175);
FORCEPROP 2 LAST CDS_LIB mstr_discrete
J 0
(-1550 1975);
PAINT ORANGE (-1550 1975);
DISPLAY INVISIBLE (-1550 1975);
FORCEPROP 2 LAST SEC_TYPE 0402
J 0
(-1600 2175);
DISPLAY 1.021277 (-1600 2175);
PAINT ORANGE (-1600 2175);
DISPLAY INVISIBLE (-1600 2175);
FORCEADD TAP..3
(-1500 1525);
FORCEPROP 3 LASTPIN (-1500 1475) SIG_NAME P3E_CPU0_PE1_PCH_TXP<9>
J 0
(-1490 1485);
DISPLAY 0.659574 (-1490 1485);
PAINT MONO (-1490 1485);
DISPLAY INVISIBLE (-1490 1485);
FORCEPROP 1 LASTPIN (-1500 1475) BN 9
R 1
J 0
(-1507 1463);
DISPLAY 0.617021 (-1507 1463);
PAINT GREEN (-1507 1463);
FORCEPROP 1 LAST PATH I176
J 0
(-1502 1525);
DISPLAY 0.872340 (-1502 1525);
PAINT GREEN (-1502 1525);
DISPLAY INVISIBLE (-1502 1525);
FORCEPROP 2 LAST CDS_LIB mstr_standard
J 0
(-1500 1525);
PAINT ORANGE (-1500 1525);
DISPLAY INVISIBLE (-1500 1525);
FORCEPROP 1 LAST BODY_TYPE PLUMBING
J 0
(-1450 1475);
DISPLAY 2.276596 (-1450 1475);
PAINT GREEN (-1450 1475);
DISPLAY INVISIBLE (-1450 1475);
FORCEPROP 1 LAST HDL_TAP TRUE
J 0
(-1180 1395);
DISPLAY 2.276596 (-1180 1395);
PAINT GREEN (-1180 1395);
DISPLAY INVISIBLE (-1180 1395);
FORCEADD TAP..7
(-1550 1725);
FORCEPROP 3 LASTPIN (-1550 1775) SIG_NAME P3E_CPU0_PE1_PCH_C_TXN<9>
J 0
(-1540 1785);
DISPLAY 0.659574 (-1540 1785);
PAINT MONO (-1540 1785);
DISPLAY INVISIBLE (-1540 1785);
FORCEPROP 1 LASTPIN (-1550 1775) BN 9
R 1
J 0
(-1557 1723);
DISPLAY 0.617021 (-1557 1723);
PAINT GREEN (-1557 1723);
FORCEPROP 1 LAST PATH I177
J 0
(-1552 1725);
DISPLAY 0.872340 (-1552 1725);
PAINT GREEN (-1552 1725);
DISPLAY INVISIBLE (-1552 1725);
FORCEPROP 2 LAST CDS_LIB mstr_standard
J 0
(-1550 1725);
PAINT ORANGE (-1550 1725);
DISPLAY INVISIBLE (-1550 1725);
FORCEPROP 1 LAST BODY_TYPE PLUMBING
J 0
(-1500 1725);
DISPLAY 2.276596 (-1500 1725);
PAINT GREEN (-1500 1725);
DISPLAY INVISIBLE (-1500 1725);
FORCEPROP 1 LAST HDL_TAP TRUE
J 0
(-1230 1595);
DISPLAY 2.276596 (-1230 1595);
PAINT GREEN (-1230 1595);
DISPLAY INVISIBLE (-1230 1595);
FORCEADD TAP..7
(-1750 1725);
FORCEPROP 3 LASTPIN (-1750 1775) SIG_NAME P3E_CPU0_PE1_PCH_C_TXN<10>
J 0
(-1740 1785);
DISPLAY 0.659574 (-1740 1785);
PAINT MONO (-1740 1785);
DISPLAY INVISIBLE (-1740 1785);
FORCEPROP 1 LASTPIN (-1750 1775) BN 10
R 1
J 0
(-1757 1723);
DISPLAY 0.617021 (-1757 1723);
PAINT GREEN (-1757 1723);
FORCEPROP 1 LAST PATH I178
J 0
(-1752 1725);
DISPLAY 0.872340 (-1752 1725);
PAINT GREEN (-1752 1725);
DISPLAY INVISIBLE (-1752 1725);
FORCEPROP 2 LAST CDS_LIB mstr_standard
J 0
(-1750 1725);
PAINT ORANGE (-1750 1725);
DISPLAY INVISIBLE (-1750 1725);
FORCEPROP 1 LAST BODY_TYPE PLUMBING
J 0
(-1700 1725);
DISPLAY 2.276596 (-1700 1725);
PAINT GREEN (-1700 1725);
DISPLAY INVISIBLE (-1700 1725);
FORCEPROP 1 LAST HDL_TAP TRUE
J 0
(-1430 1595);
DISPLAY 2.276596 (-1430 1595);
PAINT GREEN (-1430 1595);
DISPLAY INVISIBLE (-1430 1595);
FORCEADD TAP..3
(-1700 1525);
FORCEPROP 3 LASTPIN (-1700 1475) SIG_NAME P3E_CPU0_PE1_PCH_TXP<10>
J 0
(-1690 1485);
DISPLAY 0.659574 (-1690 1485);
PAINT MONO (-1690 1485);
DISPLAY INVISIBLE (-1690 1485);
FORCEPROP 1 LASTPIN (-1700 1475) BN 10
R 1
J 0
(-1707 1463);
DISPLAY 0.617021 (-1707 1463);
PAINT GREEN (-1707 1463);
FORCEPROP 1 LAST PATH I179
J 0
(-1702 1525);
DISPLAY 0.872340 (-1702 1525);
PAINT GREEN (-1702 1525);
DISPLAY INVISIBLE (-1702 1525);
FORCEPROP 2 LAST CDS_LIB mstr_standard
J 0
(-1700 1525);
PAINT ORANGE (-1700 1525);
DISPLAY INVISIBLE (-1700 1525);
FORCEPROP 1 LAST BODY_TYPE PLUMBING
J 0
(-1650 1475);
DISPLAY 2.276596 (-1650 1475);
PAINT GREEN (-1650 1475);
DISPLAY INVISIBLE (-1650 1475);
FORCEPROP 1 LAST HDL_TAP TRUE
J 0
(-1380 1395);
DISPLAY 2.276596 (-1380 1395);
PAINT GREEN (-1380 1395);
DISPLAY INVISIBLE (-1380 1395);
FORCEADD TAP..3
(-300 3900);
FORCEPROP 3 LASTPIN (-300 3850) SIG_NAME P3E_CPU0_PE2_SS_TXN<13>
J 0
(-290 3860);
DISPLAY 0.659574 (-290 3860);
PAINT MONO (-290 3860);
DISPLAY INVISIBLE (-290 3860);
FORCEPROP 1 LASTPIN (-300 3850) BN 13
R 1
J 0
(-307 3838);
DISPLAY 0.617021 (-307 3838);
PAINT GREEN (-307 3838);
FORCEPROP 1 LAST PATH I18
J 0
(-302 3900);
DISPLAY 0.872340 (-302 3900);
PAINT GREEN (-302 3900);
DISPLAY INVISIBLE (-302 3900);
FORCEPROP 2 LAST CDS_LIB mstr_standard
J 0
(-300 3900);
PAINT ORANGE (-300 3900);
DISPLAY INVISIBLE (-300 3900);
FORCEPROP 1 LAST BODY_TYPE PLUMBING
J 0
(-250 3850);
DISPLAY 2.276596 (-250 3850);
PAINT GREEN (-250 3850);
DISPLAY INVISIBLE (-250 3850);
FORCEPROP 1 LAST HDL_TAP TRUE
J 0
(20 3770);
DISPLAY 2.276596 (20 3770);
PAINT GREEN (20 3770);
DISPLAY INVISIBLE (20 3770);
FORCEADD CAP..1
R 2
(-1700 1275);
FORCEPROP 0 LAST GROUP PCIE_UPLINK
J 0
(-1850 1425);
DISPLAY 0.638298 (-1850 1425);
PAINT BROWN (-1850 1425);
DISPLAY BOTH (-1850 1425);
FORCEPROP 1 LAST LOCATION C6B16
J 2
(-1750 1375);
DISPLAY 0.617021 (-1750 1375);
PAINT AQUA (-1750 1375);
FORCEPROP 1 LAST VALUE 0.22UF
J 2
(-1750 1325);
DISPLAY 0.617021 (-1750 1325);
PAINT SKYBLUE (-1750 1325);
FORCEPROP 1 LASTPIN (-1700 1375) $PN 1
J 2
(-1710 1355);
DISPLAY 0.617021 (-1710 1355);
PAINT ORANGE (-1710 1355);
FORCEPROP 1 LASTPIN (-1700 1175) $PN 2
J 2
(-1710 1155);
DISPLAY 0.617021 (-1710 1155);
PAINT ORANGE (-1710 1155);
FORCEPROP 1 LAST MATERIAL X7R
J 2
(-1750 1175);
DISPLAY 0.617021 (-1750 1175);
PAINT SKYBLUE (-1750 1175);
FORCEPROP 1 LAST VOLTAGE 16V
J 2
(-1750 1275);
DISPLAY 0.617021 (-1750 1275);
PAINT SKYBLUE (-1750 1275);
FORCEPROP 1 LAST PACK_TYPE 0402
J 2
(-1750 1075);
DISPLAY 0.617021 (-1750 1075);
PAINT SKYBLUE (-1750 1075);
FORCEPROP 1 LAST TOLERANCE 10%
J 2
(-1750 1225);
DISPLAY 0.617021 (-1750 1225);
PAINT SKYBLUE (-1750 1225);
FORCEPROP 1 LAST PART_NUMBER A36096-155
J 2
(-1750 1125);
DISPLAY 0.617021 (-1750 1125);
PAINT BLUE (-1750 1125);
FORCEPROP 2 LAST ROOM OCP_STEERING
J 2
(-1700 1275);
PAINT MONO (-1700 1275);
DISPLAY INVISIBLE (-1700 1275);
FORCEPROP 1 LAST PATH I180
J 2
(-1750 1425);
DISPLAY 0.978723 (-1750 1425);
PAINT WHITE (-1750 1425);
DISPLAY INVISIBLE (-1750 1425);
FORCEPROP 2 LAST CDS_LOCATION C6B16
J 2
(-1750 1375);
DISPLAY 0.617021 (-1750 1375);
PAINT AQUA (-1750 1375);
DISPLAY INVISIBLE (-1750 1375);
FORCEPROP 2 LAST SEC 1
J 0
(-1750 1475);
DISPLAY 0.680851 (-1750 1475);
PAINT MONO (-1750 1475);
DISPLAY INVISIBLE (-1750 1475);
FORCEPROP 2 LAST CDS_LIB mstr_discrete
J 0
(-1700 1275);
PAINT ORANGE (-1700 1275);
DISPLAY INVISIBLE (-1700 1275);
FORCEPROP 2 LAST SEC_TYPE 0402
J 0
(-1750 1475);
DISPLAY 1.021277 (-1750 1475);
PAINT ORANGE (-1750 1475);
DISPLAY INVISIBLE (-1750 1475);
FORCEADD CAP..1
R 2
(-1950 1975);
FORCEPROP 0 LAST GROUP PCIE_UPLINK
J 0
(-2100 1700);
DISPLAY 0.638298 (-2100 1700);
PAINT BROWN (-2100 1700);
DISPLAY BOTH (-2100 1700);
FORCEPROP 1 LAST PACK_TYPE 0402
J 2
(-2000 1775);
DISPLAY 0.617021 (-2000 1775);
PAINT SKYBLUE (-2000 1775);
FORCEPROP 1 LAST PART_NUMBER A36096-155
J 2
(-2000 1825);
DISPLAY 0.617021 (-2000 1825);
PAINT BLUE (-2000 1825);
FORCEPROP 1 LAST MATERIAL X7R
J 2
(-2000 1875);
DISPLAY 0.617021 (-2000 1875);
PAINT SKYBLUE (-2000 1875);
FORCEPROP 1 LAST VALUE 0.22UF
J 2
(-2000 2025);
DISPLAY 0.617021 (-2000 2025);
PAINT SKYBLUE (-2000 2025);
FORCEPROP 1 LASTPIN (-1950 2075) $PN 1
J 2
(-1960 2055);
DISPLAY 0.617021 (-1960 2055);
PAINT ORANGE (-1960 2055);
FORCEPROP 1 LAST TOLERANCE 10%
J 2
(-2000 1925);
DISPLAY 0.617021 (-2000 1925);
PAINT SKYBLUE (-2000 1925);
FORCEPROP 1 LASTPIN (-1950 1875) $PN 2
J 2
(-1960 1855);
DISPLAY 0.617021 (-1960 1855);
PAINT ORANGE (-1960 1855);
FORCEPROP 1 LAST VOLTAGE 16V
J 2
(-2000 1975);
DISPLAY 0.617021 (-2000 1975);
PAINT SKYBLUE (-2000 1975);
FORCEPROP 1 LAST LOCATION C6B14
J 2
(-2000 2075);
DISPLAY 0.617021 (-2000 2075);
PAINT AQUA (-2000 2075);
FORCEPROP 2 LAST ROOM OCP_STEERING
J 2
(-1950 1975);
PAINT MONO (-1950 1975);
DISPLAY INVISIBLE (-1950 1975);
FORCEPROP 1 LAST PATH I181
J 2
(-2000 2125);
DISPLAY 0.978723 (-2000 2125);
PAINT WHITE (-2000 2125);
DISPLAY INVISIBLE (-2000 2125);
FORCEPROP 2 LAST CDS_LOCATION C6B14
J 2
(-2000 2075);
DISPLAY 0.617021 (-2000 2075);
PAINT AQUA (-2000 2075);
DISPLAY INVISIBLE (-2000 2075);
FORCEPROP 2 LAST SEC 1
J 0
(-2000 2175);
DISPLAY 0.680851 (-2000 2175);
PAINT MONO (-2000 2175);
DISPLAY INVISIBLE (-2000 2175);
FORCEPROP 2 LAST CDS_LIB mstr_discrete
J 0
(-1950 1975);
PAINT ORANGE (-1950 1975);
DISPLAY INVISIBLE (-1950 1975);
FORCEPROP 2 LAST SEC_TYPE 0402
J 0
(-2000 2175);
DISPLAY 1.021277 (-2000 2175);
PAINT ORANGE (-2000 2175);
DISPLAY INVISIBLE (-2000 2175);
FORCEADD TAP..3
(-1900 1525);
FORCEPROP 3 LASTPIN (-1900 1475) SIG_NAME P3E_CPU0_PE1_PCH_TXP<11>
J 0
(-1890 1485);
DISPLAY 0.659574 (-1890 1485);
PAINT MONO (-1890 1485);
DISPLAY INVISIBLE (-1890 1485);
FORCEPROP 1 LASTPIN (-1900 1475) BN 11
R 1
J 0
(-1907 1463);
DISPLAY 0.617021 (-1907 1463);
PAINT GREEN (-1907 1463);
FORCEPROP 1 LAST PATH I182
J 0
(-1902 1525);
DISPLAY 0.872340 (-1902 1525);
PAINT GREEN (-1902 1525);
DISPLAY INVISIBLE (-1902 1525);
FORCEPROP 2 LAST CDS_LIB mstr_standard
J 0
(-1900 1525);
PAINT ORANGE (-1900 1525);
DISPLAY INVISIBLE (-1900 1525);
FORCEPROP 1 LAST BODY_TYPE PLUMBING
J 0
(-1850 1475);
DISPLAY 2.276596 (-1850 1475);
PAINT GREEN (-1850 1475);
DISPLAY INVISIBLE (-1850 1475);
FORCEPROP 1 LAST HDL_TAP TRUE
J 0
(-1580 1395);
DISPLAY 2.276596 (-1580 1395);
PAINT GREEN (-1580 1395);
DISPLAY INVISIBLE (-1580 1395);
FORCEADD TAP..7
(-1950 1725);
FORCEPROP 3 LASTPIN (-1950 1775) SIG_NAME P3E_CPU0_PE1_PCH_C_TXN<11>
J 0
(-1940 1785);
DISPLAY 0.659574 (-1940 1785);
PAINT MONO (-1940 1785);
DISPLAY INVISIBLE (-1940 1785);
FORCEPROP 1 LASTPIN (-1950 1775) BN 11
R 1
J 0
(-1957 1723);
DISPLAY 0.617021 (-1957 1723);
PAINT GREEN (-1957 1723);
FORCEPROP 1 LAST PATH I183
J 0
(-1952 1725);
DISPLAY 0.872340 (-1952 1725);
PAINT GREEN (-1952 1725);
DISPLAY INVISIBLE (-1952 1725);
FORCEPROP 2 LAST CDS_LIB mstr_standard
J 0
(-1950 1725);
PAINT ORANGE (-1950 1725);
DISPLAY INVISIBLE (-1950 1725);
FORCEPROP 1 LAST BODY_TYPE PLUMBING
J 0
(-1900 1725);
DISPLAY 2.276596 (-1900 1725);
PAINT GREEN (-1900 1725);
DISPLAY INVISIBLE (-1900 1725);
FORCEPROP 1 LAST HDL_TAP TRUE
J 0
(-1630 1595);
DISPLAY 2.276596 (-1630 1595);
PAINT GREEN (-1630 1595);
DISPLAY INVISIBLE (-1630 1595);
FORCEADD TAP..7
(-2150 1725);
FORCEPROP 3 LASTPIN (-2150 1775) SIG_NAME P3E_CPU0_PE1_PCH_C_TXN<12>
J 0
(-2140 1785);
DISPLAY 0.659574 (-2140 1785);
PAINT MONO (-2140 1785);
DISPLAY INVISIBLE (-2140 1785);
FORCEPROP 1 LASTPIN (-2150 1775) BN 12
R 1
J 0
(-2157 1723);
DISPLAY 0.617021 (-2157 1723);
PAINT GREEN (-2157 1723);
FORCEPROP 1 LAST PATH I184
J 0
(-2152 1725);
DISPLAY 0.872340 (-2152 1725);
PAINT GREEN (-2152 1725);
DISPLAY INVISIBLE (-2152 1725);
FORCEPROP 2 LAST CDS_LIB mstr_standard
J 0
(-2150 1725);
PAINT ORANGE (-2150 1725);
DISPLAY INVISIBLE (-2150 1725);
FORCEPROP 1 LAST BODY_TYPE PLUMBING
J 0
(-2100 1725);
DISPLAY 2.276596 (-2100 1725);
PAINT GREEN (-2100 1725);
DISPLAY INVISIBLE (-2100 1725);
FORCEPROP 1 LAST HDL_TAP TRUE
J 0
(-1830 1595);
DISPLAY 2.276596 (-1830 1595);
PAINT GREEN (-1830 1595);
DISPLAY INVISIBLE (-1830 1595);
FORCEADD CAP..1
R 2
(-2350 1975);
FORCEPROP 1 LAST LOCATION C6B9
J 2
(-2400 2075);
DISPLAY 0.617021 (-2400 2075);
PAINT AQUA (-2400 2075);
FORCEPROP 1 LASTPIN (-2350 1875) $PN 2
J 2
(-2360 1855);
DISPLAY 0.617021 (-2360 1855);
PAINT ORANGE (-2360 1855);
FORCEPROP 1 LAST MATERIAL X7R
J 2
(-2400 1875);
DISPLAY 0.617021 (-2400 1875);
PAINT SKYBLUE (-2400 1875);
FORCEPROP 1 LAST PACK_TYPE 0402
J 2
(-2400 1775);
DISPLAY 0.617021 (-2400 1775);
PAINT SKYBLUE (-2400 1775);
FORCEPROP 1 LAST PART_NUMBER A36096-155
J 2
(-2400 1825);
DISPLAY 0.617021 (-2400 1825);
PAINT BLUE (-2400 1825);
FORCEPROP 1 LAST TOLERANCE 10%
J 2
(-2400 1925);
DISPLAY 0.617021 (-2400 1925);
PAINT SKYBLUE (-2400 1925);
FORCEPROP 1 LAST VOLTAGE 16V
J 2
(-2400 1975);
DISPLAY 0.617021 (-2400 1975);
PAINT SKYBLUE (-2400 1975);
FORCEPROP 1 LAST VALUE 0.22UF
J 2
(-2400 2025);
DISPLAY 0.617021 (-2400 2025);
PAINT SKYBLUE (-2400 2025);
FORCEPROP 1 LASTPIN (-2350 2075) $PN 1
J 2
(-2360 2055);
DISPLAY 0.617021 (-2360 2055);
PAINT ORANGE (-2360 2055);
FORCEPROP 0 LAST GROUP PCIE_UPLINK
J 0
(-2500 1700);
DISPLAY 0.638298 (-2500 1700);
PAINT BROWN (-2500 1700);
DISPLAY BOTH (-2500 1700);
FORCEPROP 2 LAST ROOM OCP_STEERING
J 2
(-2350 1975);
PAINT MONO (-2350 1975);
DISPLAY INVISIBLE (-2350 1975);
FORCEPROP 1 LAST PATH I185
J 2
(-2400 2125);
DISPLAY 0.978723 (-2400 2125);
PAINT WHITE (-2400 2125);
DISPLAY INVISIBLE (-2400 2125);
FORCEPROP 2 LAST CDS_LOCATION C6B9
J 2
(-2400 2075);
DISPLAY 0.617021 (-2400 2075);
PAINT AQUA (-2400 2075);
DISPLAY INVISIBLE (-2400 2075);
FORCEPROP 2 LAST SEC 1
J 0
(-2400 2175);
DISPLAY 0.680851 (-2400 2175);
PAINT MONO (-2400 2175);
DISPLAY INVISIBLE (-2400 2175);
FORCEPROP 2 LAST CDS_LIB mstr_discrete
J 0
(-2350 1975);
PAINT ORANGE (-2350 1975);
DISPLAY INVISIBLE (-2350 1975);
FORCEPROP 2 LAST SEC_TYPE 0402
J 0
(-2400 2175);
DISPLAY 1.021277 (-2400 2175);
PAINT ORANGE (-2400 2175);
DISPLAY INVISIBLE (-2400 2175);
FORCEADD TAP..3
(-2300 1525);
FORCEPROP 3 LASTPIN (-2300 1475) SIG_NAME P3E_CPU0_PE1_PCH_TXP<13>
J 0
(-2290 1485);
DISPLAY 0.659574 (-2290 1485);
PAINT MONO (-2290 1485);
DISPLAY INVISIBLE (-2290 1485);
FORCEPROP 1 LASTPIN (-2300 1475) BN 13
R 1
J 0
(-2307 1463);
DISPLAY 0.617021 (-2307 1463);
PAINT GREEN (-2307 1463);
FORCEPROP 1 LAST PATH I186
J 0
(-2302 1525);
DISPLAY 0.872340 (-2302 1525);
PAINT GREEN (-2302 1525);
DISPLAY INVISIBLE (-2302 1525);
FORCEPROP 2 LAST CDS_LIB mstr_standard
J 0
(-2300 1525);
PAINT ORANGE (-2300 1525);
DISPLAY INVISIBLE (-2300 1525);
FORCEPROP 1 LAST BODY_TYPE PLUMBING
J 0
(-2250 1475);
DISPLAY 2.276596 (-2250 1475);
PAINT GREEN (-2250 1475);
DISPLAY INVISIBLE (-2250 1475);
FORCEPROP 1 LAST HDL_TAP TRUE
J 0
(-1980 1395);
DISPLAY 2.276596 (-1980 1395);
PAINT GREEN (-1980 1395);
DISPLAY INVISIBLE (-1980 1395);
FORCEADD CAP..1
R 2
(-2100 1275);
FORCEPROP 0 LAST GROUP PCIE_UPLINK
J 0
(-2250 1425);
DISPLAY 0.638298 (-2250 1425);
PAINT BROWN (-2250 1425);
DISPLAY BOTH (-2250 1425);
FORCEPROP 1 LASTPIN (-2100 1375) $PN 1
J 2
(-2110 1355);
DISPLAY 0.617021 (-2110 1355);
PAINT ORANGE (-2110 1355);
FORCEPROP 1 LAST VALUE 0.22UF
J 2
(-2150 1325);
DISPLAY 0.617021 (-2150 1325);
PAINT SKYBLUE (-2150 1325);
FORCEPROP 1 LAST TOLERANCE 10%
J 2
(-2150 1225);
DISPLAY 0.617021 (-2150 1225);
PAINT SKYBLUE (-2150 1225);
FORCEPROP 1 LAST MATERIAL X7R
J 2
(-2150 1175);
DISPLAY 0.617021 (-2150 1175);
PAINT SKYBLUE (-2150 1175);
FORCEPROP 1 LAST PART_NUMBER A36096-155
J 2
(-2150 1125);
DISPLAY 0.617021 (-2150 1125);
PAINT BLUE (-2150 1125);
FORCEPROP 1 LASTPIN (-2100 1175) $PN 2
J 2
(-2110 1155);
DISPLAY 0.617021 (-2110 1155);
PAINT ORANGE (-2110 1155);
FORCEPROP 1 LAST VOLTAGE 16V
J 2
(-2150 1275);
DISPLAY 0.617021 (-2150 1275);
PAINT SKYBLUE (-2150 1275);
FORCEPROP 1 LAST PACK_TYPE 0402
J 2
(-2150 1075);
DISPLAY 0.617021 (-2150 1075);
PAINT SKYBLUE (-2150 1075);
FORCEPROP 1 LAST LOCATION C6B12
J 2
(-2150 1375);
DISPLAY 0.617021 (-2150 1375);
PAINT AQUA (-2150 1375);
FORCEPROP 2 LAST ROOM OCP_STEERING
J 2
(-2100 1275);
PAINT MONO (-2100 1275);
DISPLAY INVISIBLE (-2100 1275);
FORCEPROP 1 LAST PATH I187
J 2
(-2150 1425);
DISPLAY 0.978723 (-2150 1425);
PAINT WHITE (-2150 1425);
DISPLAY INVISIBLE (-2150 1425);
FORCEPROP 2 LAST CDS_LOCATION C6B12
J 2
(-2150 1375);
DISPLAY 0.617021 (-2150 1375);
PAINT AQUA (-2150 1375);
DISPLAY INVISIBLE (-2150 1375);
FORCEPROP 2 LAST SEC 1
J 0
(-2150 1475);
DISPLAY 0.680851 (-2150 1475);
PAINT MONO (-2150 1475);
DISPLAY INVISIBLE (-2150 1475);
FORCEPROP 2 LAST CDS_LIB mstr_discrete
J 0
(-2100 1275);
PAINT ORANGE (-2100 1275);
DISPLAY INVISIBLE (-2100 1275);
FORCEPROP 2 LAST SEC_TYPE 0402
J 0
(-2150 1475);
DISPLAY 1.021277 (-2150 1475);
PAINT ORANGE (-2150 1475);
DISPLAY INVISIBLE (-2150 1475);
FORCEADD TAP..7
(-1500 725);
FORCEPROP 3 LASTPIN (-1500 775) SIG_NAME P3E_CPU0_PE1_PCH_C_TXP<9>
J 0
(-1490 785);
DISPLAY 0.659574 (-1490 785);
PAINT MONO (-1490 785);
DISPLAY INVISIBLE (-1490 785);
FORCEPROP 1 LASTPIN (-1500 775) BN 9
R 1
J 0
(-1507 723);
DISPLAY 0.617021 (-1507 723);
PAINT GREEN (-1507 723);
FORCEPROP 1 LAST PATH I188
J 0
(-1502 725);
DISPLAY 0.872340 (-1502 725);
PAINT GREEN (-1502 725);
DISPLAY INVISIBLE (-1502 725);
FORCEPROP 2 LAST CDS_LIB mstr_standard
J 0
(-1500 725);
PAINT ORANGE (-1500 725);
DISPLAY INVISIBLE (-1500 725);
FORCEPROP 1 LAST BODY_TYPE PLUMBING
J 0
(-1450 725);
DISPLAY 2.276596 (-1450 725);
PAINT GREEN (-1450 725);
DISPLAY INVISIBLE (-1450 725);
FORCEPROP 1 LAST HDL_TAP TRUE
J 0
(-1180 595);
DISPLAY 2.276596 (-1180 595);
PAINT GREEN (-1180 595);
DISPLAY INVISIBLE (-1180 595);
FORCEADD CAP..1
R 2
(-1900 975);
FORCEPROP 0 LAST GROUP PCIE_UPLINK
J 0
(-2050 700);
DISPLAY 0.638298 (-2050 700);
PAINT BROWN (-2050 700);
DISPLAY BOTH (-2050 700);
FORCEPROP 1 LASTPIN (-1900 1075) $PN 1
J 2
(-1910 1055);
DISPLAY 0.617021 (-1910 1055);
PAINT ORANGE (-1910 1055);
FORCEPROP 1 LASTPIN (-1900 875) $PN 2
J 2
(-1910 855);
DISPLAY 0.617021 (-1910 855);
PAINT ORANGE (-1910 855);
FORCEPROP 1 LAST MATERIAL X7R
J 2
(-1950 875);
DISPLAY 0.617021 (-1950 875);
PAINT SKYBLUE (-1950 875);
FORCEPROP 1 LAST VOLTAGE 16V
J 2
(-1950 975);
DISPLAY 0.617021 (-1950 975);
PAINT SKYBLUE (-1950 975);
FORCEPROP 1 LAST PACK_TYPE 0402
J 2
(-1950 775);
DISPLAY 0.617021 (-1950 775);
PAINT SKYBLUE (-1950 775);
FORCEPROP 1 LAST TOLERANCE 10%
J 2
(-1950 925);
DISPLAY 0.617021 (-1950 925);
PAINT SKYBLUE (-1950 925);
FORCEPROP 1 LAST VALUE 0.22UF
J 2
(-1950 1025);
DISPLAY 0.617021 (-1950 1025);
PAINT SKYBLUE (-1950 1025);
FORCEPROP 1 LAST PART_NUMBER A36096-155
J 2
(-1950 825);
DISPLAY 0.617021 (-1950 825);
PAINT BLUE (-1950 825);
FORCEPROP 1 LAST LOCATION C6B13
J 2
(-1950 1075);
DISPLAY 0.617021 (-1950 1075);
PAINT AQUA (-1950 1075);
FORCEPROP 2 LAST ROOM OCP_STEERING
J 2
(-1900 975);
PAINT MONO (-1900 975);
DISPLAY INVISIBLE (-1900 975);
FORCEPROP 1 LAST PATH I189
J 2
(-1950 1125);
DISPLAY 0.978723 (-1950 1125);
PAINT WHITE (-1950 1125);
DISPLAY INVISIBLE (-1950 1125);
FORCEPROP 2 LAST CDS_LOCATION C6B13
J 2
(-1950 1075);
DISPLAY 0.617021 (-1950 1075);
PAINT AQUA (-1950 1075);
DISPLAY INVISIBLE (-1950 1075);
FORCEPROP 2 LAST SEC 1
J 0
(-1950 1175);
DISPLAY 0.680851 (-1950 1175);
PAINT MONO (-1950 1175);
DISPLAY INVISIBLE (-1950 1175);
FORCEPROP 2 LAST CDS_LIB mstr_discrete
J 0
(-1900 975);
PAINT ORANGE (-1900 975);
DISPLAY INVISIBLE (-1900 975);
FORCEPROP 2 LAST SEC_TYPE 0402
J 0
(-1950 1175);
DISPLAY 1.021277 (-1950 1175);
PAINT ORANGE (-1950 1175);
DISPLAY INVISIBLE (-1950 1175);
FORCEADD TAP..7
(-350 4100);
FORCEPROP 3 LASTPIN (-350 4150) SIG_NAME P3E_CPU0_PE2_SS_C_TXP<13>
J 0
(-340 4160);
DISPLAY 0.659574 (-340 4160);
PAINT MONO (-340 4160);
DISPLAY INVISIBLE (-340 4160);
FORCEPROP 1 LASTPIN (-350 4150) BN 13
R 1
J 0
(-357 4098);
DISPLAY 0.617021 (-357 4098);
PAINT GREEN (-357 4098);
FORCEPROP 1 LAST PATH I19
J 0
(-352 4100);
DISPLAY 0.872340 (-352 4100);
PAINT GREEN (-352 4100);
DISPLAY INVISIBLE (-352 4100);
FORCEPROP 2 LAST CDS_LIB mstr_standard
J 0
(-350 4100);
PAINT ORANGE (-350 4100);
DISPLAY INVISIBLE (-350 4100);
FORCEPROP 1 LAST BODY_TYPE PLUMBING
J 0
(-300 4100);
DISPLAY 2.276596 (-300 4100);
PAINT GREEN (-300 4100);
DISPLAY INVISIBLE (-300 4100);
FORCEPROP 1 LAST HDL_TAP TRUE
J 0
(-30 3970);
DISPLAY 2.276596 (-30 3970);
PAINT GREEN (-30 3970);
DISPLAY INVISIBLE (-30 3970);
FORCEADD TAP..7
(-1700 725);
FORCEPROP 3 LASTPIN (-1700 775) SIG_NAME P3E_CPU0_PE1_PCH_C_TXP<10>
J 0
(-1690 785);
DISPLAY 0.659574 (-1690 785);
PAINT MONO (-1690 785);
DISPLAY INVISIBLE (-1690 785);
FORCEPROP 1 LASTPIN (-1700 775) BN 10
R 1
J 0
(-1707 723);
DISPLAY 0.617021 (-1707 723);
PAINT GREEN (-1707 723);
FORCEPROP 1 LAST PATH I190
J 0
(-1702 725);
DISPLAY 0.872340 (-1702 725);
PAINT GREEN (-1702 725);
DISPLAY INVISIBLE (-1702 725);
FORCEPROP 2 LAST CDS_LIB mstr_standard
J 0
(-1700 725);
PAINT ORANGE (-1700 725);
DISPLAY INVISIBLE (-1700 725);
FORCEPROP 1 LAST BODY_TYPE PLUMBING
J 0
(-1650 725);
DISPLAY 2.276596 (-1650 725);
PAINT GREEN (-1650 725);
DISPLAY INVISIBLE (-1650 725);
FORCEPROP 1 LAST HDL_TAP TRUE
J 0
(-1380 595);
DISPLAY 2.276596 (-1380 595);
PAINT GREEN (-1380 595);
DISPLAY INVISIBLE (-1380 595);
FORCEADD TAP..7
(-1900 725);
FORCEPROP 3 LASTPIN (-1900 775) SIG_NAME P3E_CPU0_PE1_PCH_C_TXP<11>
J 0
(-1890 785);
DISPLAY 0.659574 (-1890 785);
PAINT MONO (-1890 785);
DISPLAY INVISIBLE (-1890 785);
FORCEPROP 1 LASTPIN (-1900 775) BN 11
R 1
J 0
(-1907 723);
DISPLAY 0.617021 (-1907 723);
PAINT GREEN (-1907 723);
FORCEPROP 1 LAST PATH I191
J 0
(-1902 725);
DISPLAY 0.872340 (-1902 725);
PAINT GREEN (-1902 725);
DISPLAY INVISIBLE (-1902 725);
FORCEPROP 2 LAST CDS_LIB mstr_standard
J 0
(-1900 725);
PAINT ORANGE (-1900 725);
DISPLAY INVISIBLE (-1900 725);
FORCEPROP 1 LAST BODY_TYPE PLUMBING
J 0
(-1850 725);
DISPLAY 2.276596 (-1850 725);
PAINT GREEN (-1850 725);
DISPLAY INVISIBLE (-1850 725);
FORCEPROP 1 LAST HDL_TAP TRUE
J 0
(-1580 595);
DISPLAY 2.276596 (-1580 595);
PAINT GREEN (-1580 595);
DISPLAY INVISIBLE (-1580 595);
FORCEADD TAP..7
(-2100 725);
FORCEPROP 3 LASTPIN (-2100 775) SIG_NAME P3E_CPU0_PE1_PCH_C_TXP<12>
J 0
(-2090 785);
DISPLAY 0.659574 (-2090 785);
PAINT MONO (-2090 785);
DISPLAY INVISIBLE (-2090 785);
FORCEPROP 1 LASTPIN (-2100 775) BN 12
R 1
J 0
(-2107 723);
DISPLAY 0.617021 (-2107 723);
PAINT GREEN (-2107 723);
FORCEPROP 1 LAST PATH I192
J 0
(-2102 725);
DISPLAY 0.872340 (-2102 725);
PAINT GREEN (-2102 725);
DISPLAY INVISIBLE (-2102 725);
FORCEPROP 2 LAST CDS_LIB mstr_standard
J 0
(-2100 725);
PAINT ORANGE (-2100 725);
DISPLAY INVISIBLE (-2100 725);
FORCEPROP 1 LAST BODY_TYPE PLUMBING
J 0
(-2050 725);
DISPLAY 2.276596 (-2050 725);
PAINT GREEN (-2050 725);
DISPLAY INVISIBLE (-2050 725);
FORCEPROP 1 LAST HDL_TAP TRUE
J 0
(-1780 595);
DISPLAY 2.276596 (-1780 595);
PAINT GREEN (-1780 595);
DISPLAY INVISIBLE (-1780 595);
FORCEADD CAP..1
R 2
(-2300 975);
FORCEPROP 0 LAST GROUP PCIE_UPLINK
J 0
(-2450 700);
DISPLAY 0.638298 (-2450 700);
PAINT BROWN (-2450 700);
DISPLAY BOTH (-2450 700);
FORCEPROP 1 LAST LOCATION C6B10
J 2
(-2350 1075);
DISPLAY 0.617021 (-2350 1075);
PAINT AQUA (-2350 1075);
FORCEPROP 1 LAST VALUE 0.22UF
J 2
(-2350 1025);
DISPLAY 0.617021 (-2350 1025);
PAINT SKYBLUE (-2350 1025);
FORCEPROP 1 LASTPIN (-2300 1075) $PN 1
J 2
(-2310 1055);
DISPLAY 0.617021 (-2310 1055);
PAINT ORANGE (-2310 1055);
FORCEPROP 1 LASTPIN (-2300 875) $PN 2
J 2
(-2310 855);
DISPLAY 0.617021 (-2310 855);
PAINT ORANGE (-2310 855);
FORCEPROP 1 LAST MATERIAL X7R
J 2
(-2350 875);
DISPLAY 0.617021 (-2350 875);
PAINT SKYBLUE (-2350 875);
FORCEPROP 1 LAST VOLTAGE 16V
J 2
(-2350 975);
DISPLAY 0.617021 (-2350 975);
PAINT SKYBLUE (-2350 975);
FORCEPROP 1 LAST PACK_TYPE 0402
J 2
(-2350 775);
DISPLAY 0.617021 (-2350 775);
PAINT SKYBLUE (-2350 775);
FORCEPROP 1 LAST TOLERANCE 10%
J 2
(-2350 925);
DISPLAY 0.617021 (-2350 925);
PAINT SKYBLUE (-2350 925);
FORCEPROP 1 LAST PART_NUMBER A36096-155
J 2
(-2350 825);
DISPLAY 0.617021 (-2350 825);
PAINT BLUE (-2350 825);
FORCEPROP 2 LAST ROOM OCP_STEERING
J 2
(-2300 975);
PAINT MONO (-2300 975);
DISPLAY INVISIBLE (-2300 975);
FORCEPROP 1 LAST PATH I193
J 2
(-2350 1125);
DISPLAY 0.978723 (-2350 1125);
PAINT WHITE (-2350 1125);
DISPLAY INVISIBLE (-2350 1125);
FORCEPROP 2 LAST CDS_LOCATION C6B10
J 2
(-2350 1075);
DISPLAY 0.617021 (-2350 1075);
PAINT AQUA (-2350 1075);
DISPLAY INVISIBLE (-2350 1075);
FORCEPROP 2 LAST SEC 1
J 0
(-2350 1175);
DISPLAY 0.680851 (-2350 1175);
PAINT MONO (-2350 1175);
DISPLAY INVISIBLE (-2350 1175);
FORCEPROP 2 LAST CDS_LIB mstr_discrete
J 0
(-2300 975);
PAINT ORANGE (-2300 975);
DISPLAY INVISIBLE (-2300 975);
FORCEPROP 2 LAST SEC_TYPE 0402
J 0
(-2350 1175);
DISPLAY 1.021277 (-2350 1175);
PAINT ORANGE (-2350 1175);
DISPLAY INVISIBLE (-2350 1175);
FORCEADD TAP..7
(-2300 725);
FORCEPROP 3 LASTPIN (-2300 775) SIG_NAME P3E_CPU0_PE1_PCH_C_TXP<13>
J 0
(-2290 785);
DISPLAY 0.659574 (-2290 785);
PAINT MONO (-2290 785);
DISPLAY INVISIBLE (-2290 785);
FORCEPROP 1 LASTPIN (-2300 775) BN 13
R 1
J 0
(-2307 723);
DISPLAY 0.617021 (-2307 723);
PAINT GREEN (-2307 723);
FORCEPROP 1 LAST PATH I194
J 0
(-2302 725);
DISPLAY 0.872340 (-2302 725);
PAINT GREEN (-2302 725);
DISPLAY INVISIBLE (-2302 725);
FORCEPROP 2 LAST CDS_LIB mstr_standard
J 0
(-2300 725);
PAINT ORANGE (-2300 725);
DISPLAY INVISIBLE (-2300 725);
FORCEPROP 1 LAST BODY_TYPE PLUMBING
J 0
(-2250 725);
DISPLAY 2.276596 (-2250 725);
PAINT GREEN (-2250 725);
DISPLAY INVISIBLE (-2250 725);
FORCEPROP 1 LAST HDL_TAP TRUE
J 0
(-1980 595);
DISPLAY 2.276596 (-1980 595);
PAINT GREEN (-1980 595);
DISPLAY INVISIBLE (-1980 595);
FORCEADD TAP..3
(-2500 1525);
FORCEPROP 3 LASTPIN (-2500 1475) SIG_NAME P3E_CPU0_PE1_PCH_TXP<14>
J 0
(-2490 1485);
DISPLAY 0.659574 (-2490 1485);
PAINT MONO (-2490 1485);
DISPLAY INVISIBLE (-2490 1485);
FORCEPROP 1 LASTPIN (-2500 1475) BN 14
R 1
J 0
(-2507 1463);
DISPLAY 0.617021 (-2507 1463);
PAINT GREEN (-2507 1463);
FORCEPROP 1 LAST PATH I195
J 0
(-2502 1525);
DISPLAY 0.872340 (-2502 1525);
PAINT GREEN (-2502 1525);
DISPLAY INVISIBLE (-2502 1525);
FORCEPROP 2 LAST CDS_LIB mstr_standard
J 0
(-2500 1525);
PAINT ORANGE (-2500 1525);
DISPLAY INVISIBLE (-2500 1525);
FORCEPROP 1 LAST BODY_TYPE PLUMBING
J 0
(-2450 1475);
DISPLAY 2.276596 (-2450 1475);
PAINT GREEN (-2450 1475);
DISPLAY INVISIBLE (-2450 1475);
FORCEPROP 1 LAST HDL_TAP TRUE
J 0
(-2180 1395);
DISPLAY 2.276596 (-2180 1395);
PAINT GREEN (-2180 1395);
DISPLAY INVISIBLE (-2180 1395);
FORCEADD CAP..1
R 2
(-2750 1975);
FORCEPROP 1 LAST VALUE 0.22UF
J 2
(-2800 2025);
DISPLAY 0.617021 (-2800 2025);
PAINT SKYBLUE (-2800 2025);
FORCEPROP 1 LAST VOLTAGE 16V
J 2
(-2800 1975);
DISPLAY 0.617021 (-2800 1975);
PAINT SKYBLUE (-2800 1975);
FORCEPROP 1 LASTPIN (-2750 2075) $PN 1
J 2
(-2760 2055);
DISPLAY 0.617021 (-2760 2055);
PAINT ORANGE (-2760 2055);
FORCEPROP 1 LASTPIN (-2750 1875) $PN 2
J 2
(-2760 1855);
DISPLAY 0.617021 (-2760 1855);
PAINT ORANGE (-2760 1855);
FORCEPROP 1 LAST MATERIAL X7R
J 2
(-2800 1875);
DISPLAY 0.617021 (-2800 1875);
PAINT SKYBLUE (-2800 1875);
FORCEPROP 1 LAST PART_NUMBER A36096-155
J 2
(-2800 1825);
DISPLAY 0.617021 (-2800 1825);
PAINT BLUE (-2800 1825);
FORCEPROP 1 LAST LOCATION C6B4
J 2
(-2800 2075);
DISPLAY 0.617021 (-2800 2075);
PAINT AQUA (-2800 2075);
FORCEPROP 1 LAST TOLERANCE 10%
J 2
(-2800 1925);
DISPLAY 0.617021 (-2800 1925);
PAINT SKYBLUE (-2800 1925);
FORCEPROP 1 LAST PACK_TYPE 0402
J 2
(-2800 1775);
DISPLAY 0.617021 (-2800 1775);
PAINT SKYBLUE (-2800 1775);
FORCEPROP 0 LAST GROUP PCIE_UPLINK
J 0
(-3000 1700);
DISPLAY 0.638298 (-3000 1700);
PAINT BROWN (-3000 1700);
DISPLAY BOTH (-3000 1700);
FORCEPROP 2 LAST ROOM OCP_STEERING
J 2
(-2750 1975);
PAINT MONO (-2750 1975);
DISPLAY INVISIBLE (-2750 1975);
FORCEPROP 1 LAST PATH I196
J 2
(-2800 2125);
DISPLAY 0.978723 (-2800 2125);
PAINT WHITE (-2800 2125);
DISPLAY INVISIBLE (-2800 2125);
FORCEPROP 2 LAST CDS_LOCATION C6B4
J 2
(-2800 2075);
DISPLAY 0.617021 (-2800 2075);
PAINT AQUA (-2800 2075);
DISPLAY INVISIBLE (-2800 2075);
FORCEPROP 2 LAST SEC 1
J 0
(-2800 2175);
DISPLAY 0.680851 (-2800 2175);
PAINT MONO (-2800 2175);
DISPLAY INVISIBLE (-2800 2175);
FORCEPROP 2 LAST CDS_LIB mstr_discrete
J 0
(-2750 1975);
PAINT ORANGE (-2750 1975);
DISPLAY INVISIBLE (-2750 1975);
FORCEPROP 2 LAST SEC_TYPE 0402
J 0
(-2800 2175);
DISPLAY 1.021277 (-2800 2175);
PAINT ORANGE (-2800 2175);
DISPLAY INVISIBLE (-2800 2175);
FORCEADD TAP..3
(-2700 1525);
FORCEPROP 3 LASTPIN (-2700 1475) SIG_NAME P3E_CPU0_PE1_PCH_TXP<15>
J 0
(-2690 1485);
DISPLAY 0.659574 (-2690 1485);
PAINT MONO (-2690 1485);
DISPLAY INVISIBLE (-2690 1485);
FORCEPROP 1 LASTPIN (-2700 1475) BN 15
R 1
J 0
(-2707 1463);
DISPLAY 0.617021 (-2707 1463);
PAINT GREEN (-2707 1463);
FORCEPROP 1 LAST PATH I197
J 0
(-2702 1525);
DISPLAY 0.872340 (-2702 1525);
PAINT GREEN (-2702 1525);
DISPLAY INVISIBLE (-2702 1525);
FORCEPROP 2 LAST CDS_LIB mstr_standard
J 0
(-2700 1525);
PAINT ORANGE (-2700 1525);
DISPLAY INVISIBLE (-2700 1525);
FORCEPROP 1 LAST BODY_TYPE PLUMBING
J 0
(-2650 1475);
DISPLAY 2.276596 (-2650 1475);
PAINT GREEN (-2650 1475);
DISPLAY INVISIBLE (-2650 1475);
FORCEPROP 1 LAST HDL_TAP TRUE
J 0
(-2380 1395);
DISPLAY 2.276596 (-2380 1395);
PAINT GREEN (-2380 1395);
DISPLAY INVISIBLE (-2380 1395);
FORCEADD CAP..1
R 2
(-2500 1275);
FORCEPROP 0 LAST GROUP PCIE_UPLINK
J 0
(-2650 1425);
DISPLAY 0.638298 (-2650 1425);
PAINT BROWN (-2650 1425);
DISPLAY BOTH (-2650 1425);
FORCEPROP 1 LASTPIN (-2500 1375) $PN 1
J 2
(-2510 1355);
DISPLAY 0.617021 (-2510 1355);
PAINT ORANGE (-2510 1355);
FORCEPROP 1 LASTPIN (-2500 1175) $PN 2
J 2
(-2510 1155);
DISPLAY 0.617021 (-2510 1155);
PAINT ORANGE (-2510 1155);
FORCEPROP 1 LAST MATERIAL X7R
J 2
(-2550 1175);
DISPLAY 0.617021 (-2550 1175);
PAINT SKYBLUE (-2550 1175);
FORCEPROP 1 LAST VOLTAGE 16V
J 2
(-2550 1275);
DISPLAY 0.617021 (-2550 1275);
PAINT SKYBLUE (-2550 1275);
FORCEPROP 1 LAST PACK_TYPE 0402
J 2
(-2550 1075);
DISPLAY 0.617021 (-2550 1075);
PAINT SKYBLUE (-2550 1075);
FORCEPROP 1 LAST TOLERANCE 10%
J 2
(-2550 1225);
DISPLAY 0.617021 (-2550 1225);
PAINT SKYBLUE (-2550 1225);
FORCEPROP 1 LAST VALUE 0.22UF
J 2
(-2550 1325);
DISPLAY 0.617021 (-2550 1325);
PAINT SKYBLUE (-2550 1325);
FORCEPROP 1 LAST PART_NUMBER A36096-155
J 2
(-2550 1125);
DISPLAY 0.617021 (-2550 1125);
PAINT BLUE (-2550 1125);
FORCEPROP 1 LAST LOCATION C6B8
J 2
(-2550 1375);
DISPLAY 0.617021 (-2550 1375);
PAINT AQUA (-2550 1375);
FORCEPROP 2 LAST ROOM OCP_STEERING
J 2
(-2500 1275);
PAINT MONO (-2500 1275);
DISPLAY INVISIBLE (-2500 1275);
FORCEPROP 1 LAST PATH I198
J 2
(-2550 1425);
DISPLAY 0.978723 (-2550 1425);
PAINT WHITE (-2550 1425);
DISPLAY INVISIBLE (-2550 1425);
FORCEPROP 2 LAST CDS_LOCATION C6B8
J 2
(-2550 1375);
DISPLAY 0.617021 (-2550 1375);
PAINT AQUA (-2550 1375);
DISPLAY INVISIBLE (-2550 1375);
FORCEPROP 2 LAST SEC 1
J 0
(-2550 1475);
DISPLAY 0.680851 (-2550 1475);
PAINT MONO (-2550 1475);
DISPLAY INVISIBLE (-2550 1475);
FORCEPROP 2 LAST CDS_LIB mstr_discrete
J 0
(-2500 1275);
PAINT ORANGE (-2500 1275);
DISPLAY INVISIBLE (-2500 1275);
FORCEPROP 2 LAST SEC_TYPE 0402
J 0
(-2550 1475);
DISPLAY 1.021277 (-2550 1475);
PAINT ORANGE (-2550 1475);
DISPLAY INVISIBLE (-2550 1475);
FORCEADD OFFPAGE..1
(-2875 1575);
FORCEPROP 2 LAST $XR1 244 
J 0
(-3216 1575);
DISPLAY 0.638298 (-3216 1575);
PAINT MONO (-3216 1575);
FORCEPROP 2 LAST $XR0 30 
J 0
(-3096 1575);
DISPLAY 0.638298 (-3096 1575);
PAINT MONO (-3096 1575);
FORCEPROP 2 LAST PATH I199
J 0
(-2825 1650);
DISPLAY 1.021277 (-2825 1650);
PAINT ORANGE (-2825 1650);
DISPLAY INVISIBLE (-2825 1650);
FORCEPROP 2 LAST CDS_LIB mstr_standard
J 0
(-2875 1575);
PAINT ORANGE (-2875 1575);
DISPLAY INVISIBLE (-2875 1575);
FORCEPROP 1 LAST OFFPAGE TRUE
J 0
(-2555 1445);
PAINT GREEN (-2555 1445);
DISPLAY INVISIBLE (-2555 1445);
FORCEPROP 1 LAST COMMENT_BODY TRUE
J 0
(-2755 1475);
DISPLAY 2.276596 (-2755 1475);
PAINT GREEN (-2755 1475);
DISPLAY INVISIBLE (-2755 1475);
FORCEADD CAP..1
R 2
(-750 4350);
FORCEPROP 1 LASTPIN (-750 4450) $PN 1
J 2
(-760 4430);
DISPLAY 0.617021 (-760 4430);
PAINT ORANGE (-760 4430);
FORCEPROP 1 LASTPIN (-750 4250) $PN 2
J 2
(-760 4230);
DISPLAY 0.617021 (-760 4230);
PAINT ORANGE (-760 4230);
FORCEPROP 1 LAST MATERIAL X7R
J 2
(-800 4250);
DISPLAY 0.617021 (-800 4250);
PAINT SKYBLUE (-800 4250);
FORCEPROP 1 LAST VOLTAGE 16V
J 2
(-800 4350);
DISPLAY 0.617021 (-800 4350);
PAINT SKYBLUE (-800 4350);
FORCEPROP 1 LAST PACK_TYPE 0402
J 2
(-800 4150);
DISPLAY 0.617021 (-800 4150);
PAINT SKYBLUE (-800 4150);
FORCEPROP 1 LAST TOLERANCE 10%
J 2
(-800 4300);
DISPLAY 0.617021 (-800 4300);
PAINT SKYBLUE (-800 4300);
FORCEPROP 1 LAST VALUE 0.22UF
J 2
(-800 4400);
DISPLAY 0.617021 (-800 4400);
PAINT SKYBLUE (-800 4400);
FORCEPROP 1 LAST PART_NUMBER A36096-155
J 2
(-800 4200);
DISPLAY 0.617021 (-800 4200);
PAINT BLUE (-800 4200);
FORCEPROP 1 LAST LOCATION C7G5
J 2
(-800 4450);
DISPLAY 0.617021 (-800 4450);
PAINT AQUA (-800 4450);
FORCEPROP 2 LAST ROOM OCP_STEERING
J 2
(-750 4350);
PAINT MONO (-750 4350);
DISPLAY INVISIBLE (-750 4350);
FORCEPROP 1 LAST PATH I20
J 2
(-800 4500);
DISPLAY 0.978723 (-800 4500);
PAINT WHITE (-800 4500);
DISPLAY INVISIBLE (-800 4500);
FORCEPROP 2 LAST CDS_LOCATION C7G5
J 2
(-800 4450);
DISPLAY 0.617021 (-800 4450);
PAINT AQUA (-800 4450);
DISPLAY INVISIBLE (-800 4450);
FORCEPROP 2 LAST SEC 1
J 0
(-800 4550);
DISPLAY 0.680851 (-800 4550);
PAINT MONO (-800 4550);
DISPLAY INVISIBLE (-800 4550);
FORCEPROP 2 LAST CDS_LIB mstr_discrete
J 0
(-750 4350);
PAINT ORANGE (-750 4350);
DISPLAY INVISIBLE (-750 4350);
FORCEPROP 2 LAST SEC_TYPE 0402
J 0
(-800 4550);
DISPLAY 1.021277 (-800 4550);
PAINT ORANGE (-800 4550);
DISPLAY INVISIBLE (-800 4550);
FORCEADD TAP..7
(-2500 725);
FORCEPROP 3 LASTPIN (-2500 775) SIG_NAME P3E_CPU0_PE1_PCH_C_TXP<14>
J 0
(-2490 785);
DISPLAY 0.659574 (-2490 785);
PAINT MONO (-2490 785);
DISPLAY INVISIBLE (-2490 785);
FORCEPROP 1 LASTPIN (-2500 775) BN 14
R 1
J 0
(-2507 723);
DISPLAY 0.617021 (-2507 723);
PAINT GREEN (-2507 723);
FORCEPROP 1 LAST PATH I200
J 0
(-2502 725);
DISPLAY 0.872340 (-2502 725);
PAINT GREEN (-2502 725);
DISPLAY INVISIBLE (-2502 725);
FORCEPROP 2 LAST CDS_LIB mstr_standard
J 0
(-2500 725);
PAINT ORANGE (-2500 725);
DISPLAY INVISIBLE (-2500 725);
FORCEPROP 1 LAST BODY_TYPE PLUMBING
J 0
(-2450 725);
DISPLAY 2.276596 (-2450 725);
PAINT GREEN (-2450 725);
DISPLAY INVISIBLE (-2450 725);
FORCEPROP 1 LAST HDL_TAP TRUE
J 0
(-2180 595);
DISPLAY 2.276596 (-2180 595);
PAINT GREEN (-2180 595);
DISPLAY INVISIBLE (-2180 595);
FORCEADD CAP..1
R 2
(-2700 975);
FORCEPROP 0 LAST GROUP PCIE_UPLINK
J 0
(-2950 700);
DISPLAY 0.638298 (-2950 700);
PAINT BROWN (-2950 700);
DISPLAY BOTH (-2950 700);
FORCEPROP 1 LASTPIN (-2700 1075) $PN 1
J 2
(-2710 1055);
DISPLAY 0.617021 (-2710 1055);
PAINT ORANGE (-2710 1055);
FORCEPROP 1 LASTPIN (-2700 875) $PN 2
J 2
(-2710 855);
DISPLAY 0.617021 (-2710 855);
PAINT ORANGE (-2710 855);
FORCEPROP 1 LAST MATERIAL X7R
J 2
(-2750 875);
DISPLAY 0.617021 (-2750 875);
PAINT SKYBLUE (-2750 875);
FORCEPROP 1 LAST VOLTAGE 16V
J 2
(-2750 975);
DISPLAY 0.617021 (-2750 975);
PAINT SKYBLUE (-2750 975);
FORCEPROP 1 LAST PACK_TYPE 0402
J 2
(-2750 775);
DISPLAY 0.617021 (-2750 775);
PAINT SKYBLUE (-2750 775);
FORCEPROP 1 LAST TOLERANCE 10%
J 2
(-2750 925);
DISPLAY 0.617021 (-2750 925);
PAINT SKYBLUE (-2750 925);
FORCEPROP 1 LAST VALUE 0.22UF
J 2
(-2750 1025);
DISPLAY 0.617021 (-2750 1025);
PAINT SKYBLUE (-2750 1025);
FORCEPROP 1 LAST PART_NUMBER A36096-155
J 2
(-2750 825);
DISPLAY 0.617021 (-2750 825);
PAINT BLUE (-2750 825);
FORCEPROP 1 LAST LOCATION C6B5
J 2
(-2750 1075);
DISPLAY 0.617021 (-2750 1075);
PAINT AQUA (-2750 1075);
FORCEPROP 2 LAST ROOM OCP_STEERING
J 2
(-2700 975);
PAINT MONO (-2700 975);
DISPLAY INVISIBLE (-2700 975);
FORCEPROP 1 LAST PATH I201
J 2
(-2750 1125);
DISPLAY 0.978723 (-2750 1125);
PAINT WHITE (-2750 1125);
DISPLAY INVISIBLE (-2750 1125);
FORCEPROP 2 LAST CDS_LOCATION C6B5
J 2
(-2750 1075);
DISPLAY 0.617021 (-2750 1075);
PAINT AQUA (-2750 1075);
DISPLAY INVISIBLE (-2750 1075);
FORCEPROP 2 LAST SEC 1
J 0
(-2750 1175);
DISPLAY 0.680851 (-2750 1175);
PAINT MONO (-2750 1175);
DISPLAY INVISIBLE (-2750 1175);
FORCEPROP 2 LAST CDS_LIB mstr_discrete
J 0
(-2700 975);
PAINT ORANGE (-2700 975);
DISPLAY INVISIBLE (-2700 975);
FORCEPROP 2 LAST SEC_TYPE 0402
J 0
(-2750 1175);
DISPLAY 1.021277 (-2750 1175);
PAINT ORANGE (-2750 1175);
DISPLAY INVISIBLE (-2750 1175);
FORCEADD TAP..7
(-2700 725);
FORCEPROP 3 LASTPIN (-2700 775) SIG_NAME P3E_CPU0_PE1_PCH_C_TXP<15>
J 0
(-2690 785);
DISPLAY 0.659574 (-2690 785);
PAINT MONO (-2690 785);
DISPLAY INVISIBLE (-2690 785);
FORCEPROP 1 LASTPIN (-2700 775) BN 15
R 1
J 0
(-2707 723);
DISPLAY 0.617021 (-2707 723);
PAINT GREEN (-2707 723);
FORCEPROP 1 LAST PATH I202
J 0
(-2702 725);
DISPLAY 0.872340 (-2702 725);
PAINT GREEN (-2702 725);
DISPLAY INVISIBLE (-2702 725);
FORCEPROP 2 LAST CDS_LIB mstr_standard
J 0
(-2700 725);
PAINT ORANGE (-2700 725);
DISPLAY INVISIBLE (-2700 725);
FORCEPROP 1 LAST BODY_TYPE PLUMBING
J 0
(-2650 725);
DISPLAY 2.276596 (-2650 725);
PAINT GREEN (-2650 725);
DISPLAY INVISIBLE (-2650 725);
FORCEPROP 1 LAST HDL_TAP TRUE
J 0
(-2380 595);
DISPLAY 2.276596 (-2380 595);
PAINT GREEN (-2380 595);
DISPLAY INVISIBLE (-2380 595);
FORCEADD OFFPAGE..2
(-1050 1675);
FORCEPROP 2 LAST $XR0 117 
J 0
(-861 1675);
DISPLAY 0.638298 (-861 1675);
PAINT MONO (-861 1675);
FORCEPROP 2 LAST PATH I203
J 0
(-875 1750);
DISPLAY 1.021277 (-875 1750);
PAINT ORANGE (-875 1750);
DISPLAY INVISIBLE (-875 1750);
FORCEPROP 2 LAST CDS_LIB mstr_standard
J 0
(-1050 1675);
PAINT ORANGE (-1050 1675);
DISPLAY INVISIBLE (-1050 1675);
FORCEPROP 1 LAST OFFPAGE TRUE
J 0
(-725 1550);
DISPLAY 0.872340 (-725 1550);
PAINT GREEN (-725 1550);
DISPLAY INVISIBLE (-725 1550);
FORCEPROP 1 LAST COMMENT_BODY TRUE
J 0
(-1095 1580);
DISPLAY 0.872340 (-1095 1580);
PAINT GREEN (-1095 1580);
DISPLAY INVISIBLE (-1095 1580);
FORCEADD OFFPAGE..2
(-1000 675);
FORCEPROP 2 LAST $XR0 117 
J 0
(-811 675);
DISPLAY 0.638298 (-811 675);
PAINT MONO (-811 675);
FORCEPROP 2 LAST PATH I204
J 0
(-825 750);
DISPLAY 1.021277 (-825 750);
PAINT ORANGE (-825 750);
DISPLAY INVISIBLE (-825 750);
FORCEPROP 2 LAST CDS_LIB mstr_standard
J 0
(-1000 675);
PAINT ORANGE (-1000 675);
DISPLAY INVISIBLE (-1000 675);
FORCEPROP 1 LAST OFFPAGE TRUE
J 0
(-675 550);
DISPLAY 0.872340 (-675 550);
PAINT GREEN (-675 550);
DISPLAY INVISIBLE (-675 550);
FORCEPROP 1 LAST COMMENT_BODY TRUE
J 0
(-1045 580);
DISPLAY 0.872340 (-1045 580);
PAINT GREEN (-1045 580);
DISPLAY INVISIBLE (-1045 580);
FORCEADD CAP..1
R 2
(1800 2025);
FORCEPROP 1 LAST LOCATION C3M25
J 2
(1750 2125);
DISPLAY 0.617021 (1750 2125);
PAINT AQUA (1750 2125);
FORCEPROP 1 LASTPIN (1800 2125) $PN 1
J 2
(1790 2105);
DISPLAY 0.617021 (1790 2105);
PAINT ORANGE (1790 2105);
FORCEPROP 1 LAST VOLTAGE 16V
J 2
(1750 2025);
DISPLAY 0.617021 (1750 2025);
PAINT SKYBLUE (1750 2025);
FORCEPROP 1 LAST PACK_TYPE 0402
J 2
(1750 1825);
DISPLAY 0.617021 (1750 1825);
PAINT SKYBLUE (1750 1825);
FORCEPROP 1 LAST PART_NUMBER A36096-155
J 2
(1750 1875);
DISPLAY 0.617021 (1750 1875);
PAINT BLUE (1750 1875);
FORCEPROP 1 LAST VALUE 0.22UF
J 2
(1750 2075);
DISPLAY 0.617021 (1750 2075);
PAINT SKYBLUE (1750 2075);
FORCEPROP 1 LAST MATERIAL X7R
J 2
(1750 1925);
DISPLAY 0.617021 (1750 1925);
PAINT SKYBLUE (1750 1925);
FORCEPROP 1 LAST TOLERANCE 10%
J 2
(1750 1975);
DISPLAY 0.617021 (1750 1975);
PAINT SKYBLUE (1750 1975);
FORCEPROP 1 LASTPIN (1800 1925) $PN 2
J 2
(1790 1905);
DISPLAY 0.617021 (1790 1905);
PAINT ORANGE (1790 1905);
FORCEPROP 0 LAST GROUP PCIE_UPLINK
J 0
(1650 1750);
DISPLAY 0.638298 (1650 1750);
PAINT BROWN (1650 1750);
DISPLAY BOTH (1650 1750);
FORCEPROP 2 LAST ROOM OCP_STEERING
J 2
(1800 2025);
PAINT MONO (1800 2025);
DISPLAY INVISIBLE (1800 2025);
FORCEPROP 1 LAST PATH I205
J 2
(1750 2175);
DISPLAY 0.978723 (1750 2175);
PAINT WHITE (1750 2175);
DISPLAY INVISIBLE (1750 2175);
FORCEPROP 2 LAST CDS_LOCATION C3M25
J 2
(1750 2125);
DISPLAY 0.617021 (1750 2125);
PAINT AQUA (1750 2125);
DISPLAY INVISIBLE (1750 2125);
FORCEPROP 2 LAST $SEC 1
J 0
(1750 2225);
DISPLAY 0.680851 (1750 2225);
PAINT MONO (1750 2225);
DISPLAY INVISIBLE (1750 2225);
FORCEPROP 2 LAST CDS_SEC 1
J 0
(1750 2225);
DISPLAY 1.021277 (1750 2225);
PAINT ORANGE (1750 2225);
DISPLAY INVISIBLE (1750 2225);
FORCEPROP 2 LAST CDS_LIB mstr_discrete
J 0
(1800 2025);
PAINT ORANGE (1800 2025);
DISPLAY INVISIBLE (1800 2025);
FORCEADD CAP..1
R 2
(2400 2325);
FORCEPROP 0 LAST GROUP PCIE_UPLINK
J 0
(2250 2575);
DISPLAY 0.638298 (2250 2575);
PAINT BROWN (2250 2575);
DISPLAY BOTH (2250 2575);
FORCEPROP 1 LAST VALUE 0.22UF
J 2
(2350 2375);
DISPLAY 0.617021 (2350 2375);
PAINT SKYBLUE (2350 2375);
FORCEPROP 1 LAST PACK_TYPE 0402
J 2
(2350 2125);
DISPLAY 0.617021 (2350 2125);
PAINT SKYBLUE (2350 2125);
FORCEPROP 1 LASTPIN (2400 2225) $PN 2
J 2
(2390 2205);
DISPLAY 0.617021 (2390 2205);
PAINT ORANGE (2390 2205);
FORCEPROP 1 LAST MATERIAL X7R
J 2
(2350 2225);
DISPLAY 0.617021 (2350 2225);
PAINT SKYBLUE (2350 2225);
FORCEPROP 1 LAST TOLERANCE 10%
J 2
(2350 2275);
DISPLAY 0.617021 (2350 2275);
PAINT SKYBLUE (2350 2275);
FORCEPROP 1 LAST VOLTAGE 16V
J 2
(2350 2325);
DISPLAY 0.617021 (2350 2325);
PAINT SKYBLUE (2350 2325);
FORCEPROP 1 LASTPIN (2400 2425) $PN 1
J 2
(2390 2405);
DISPLAY 0.617021 (2390 2405);
PAINT ORANGE (2390 2405);
FORCEPROP 1 LAST LOCATION C3M34
J 2
(2350 2425);
DISPLAY 0.617021 (2350 2425);
PAINT AQUA (2350 2425);
FORCEPROP 1 LAST PART_NUMBER A36096-155
J 2
(2350 2175);
DISPLAY 0.617021 (2350 2175);
PAINT BLUE (2350 2175);
FORCEPROP 2 LAST ROOM OCP_STEERING
J 2
(2400 2325);
PAINT MONO (2400 2325);
DISPLAY INVISIBLE (2400 2325);
FORCEPROP 1 LAST PATH I206
J 2
(2350 2475);
DISPLAY 0.978723 (2350 2475);
PAINT WHITE (2350 2475);
DISPLAY INVISIBLE (2350 2475);
FORCEPROP 2 LAST CDS_LOCATION C3M34
J 2
(2350 2425);
DISPLAY 0.617021 (2350 2425);
PAINT AQUA (2350 2425);
DISPLAY INVISIBLE (2350 2425);
FORCEPROP 2 LAST $SEC 1
J 0
(2350 2525);
DISPLAY 0.680851 (2350 2525);
PAINT MONO (2350 2525);
DISPLAY INVISIBLE (2350 2525);
FORCEPROP 2 LAST CDS_SEC 1
J 0
(2350 2525);
DISPLAY 1.021277 (2350 2525);
PAINT ORANGE (2350 2525);
DISPLAY INVISIBLE (2350 2525);
FORCEPROP 2 LAST CDS_LIB mstr_discrete
J 0
(2400 2325);
PAINT ORANGE (2400 2325);
DISPLAY INVISIBLE (2400 2325);
FORCEADD OFFPAGE..2
(2700 1725);
FORCEPROP 2 LAST $XR1 244 
J 0
(2979 1725);
DISPLAY 0.638298 (2979 1725);
PAINT MONO (2979 1725);
FORCEPROP 2 LAST $XR0 30 
J 0
(2889 1725);
DISPLAY 0.638298 (2889 1725);
PAINT MONO (2889 1725);
FORCEPROP 2 LAST PATH I207
J 0
(2875 1800);
DISPLAY 1.021277 (2875 1800);
PAINT ORANGE (2875 1800);
DISPLAY INVISIBLE (2875 1800);
FORCEPROP 2 LAST CDS_LIB mstr_standard
J 0
(2700 1725);
PAINT ORANGE (2700 1725);
DISPLAY INVISIBLE (2700 1725);
FORCEPROP 1 LAST OFFPAGE TRUE
J 0
(3025 1600);
DISPLAY 0.872340 (3025 1600);
PAINT GREEN (3025 1600);
DISPLAY INVISIBLE (3025 1600);
FORCEPROP 1 LAST COMMENT_BODY TRUE
J 0
(2655 1630);
DISPLAY 0.872340 (2655 1630);
PAINT GREEN (2655 1630);
DISPLAY INVISIBLE (2655 1630);
FORCEADD OFFPAGE..2
(2750 725);
FORCEPROP 2 LAST $XR1 244 
J 0
(3029 725);
DISPLAY 0.638298 (3029 725);
PAINT MONO (3029 725);
FORCEPROP 2 LAST $XR0 30 
J 0
(2939 725);
DISPLAY 0.638298 (2939 725);
PAINT MONO (2939 725);
FORCEPROP 2 LAST PATH I208
J 0
(2925 800);
DISPLAY 1.021277 (2925 800);
PAINT ORANGE (2925 800);
DISPLAY INVISIBLE (2925 800);
FORCEPROP 2 LAST CDS_LIB mstr_standard
J 0
(2750 725);
PAINT ORANGE (2750 725);
DISPLAY INVISIBLE (2750 725);
FORCEPROP 1 LAST OFFPAGE TRUE
J 0
(3075 600);
DISPLAY 0.872340 (3075 600);
PAINT GREEN (3075 600);
DISPLAY INVISIBLE (3075 600);
FORCEPROP 1 LAST COMMENT_BODY TRUE
J 0
(2705 630);
DISPLAY 0.872340 (2705 630);
PAINT GREEN (2705 630);
DISPLAY INVISIBLE (2705 630);
FORCEADD TAP..3
(2400 2575);
FORCEPROP 3 LASTPIN (2400 2525) SIG_NAME P3E_CPU0_PE1_PCH_R_RXP<8>
J 0
(2410 2535);
DISPLAY 0.659574 (2410 2535);
PAINT MONO (2410 2535);
DISPLAY INVISIBLE (2410 2535);
FORCEPROP 1 LASTPIN (2400 2525) BN 8
R 1
J 0
(2393 2513);
DISPLAY 0.617021 (2393 2513);
PAINT GREEN (2393 2513);
FORCEPROP 1 LAST PATH I209
J 0
(2398 2575);
DISPLAY 0.872340 (2398 2575);
PAINT GREEN (2398 2575);
DISPLAY INVISIBLE (2398 2575);
FORCEPROP 2 LAST CDS_LIB mstr_standard
J 0
(2400 2575);
PAINT ORANGE (2400 2575);
DISPLAY INVISIBLE (2400 2575);
FORCEPROP 1 LAST BODY_TYPE PLUMBING
J 0
(2450 2525);
DISPLAY 2.276596 (2450 2525);
PAINT GREEN (2450 2525);
DISPLAY INVISIBLE (2450 2525);
FORCEPROP 1 LAST HDL_TAP TRUE
J 0
(2720 2445);
DISPLAY 2.276596 (2720 2445);
PAINT GREEN (2720 2445);
DISPLAY INVISIBLE (2720 2445);
FORCEADD CAP..1
R 2
(-350 4350);
FORCEPROP 1 LASTPIN (-350 4450) $PN 1
J 2
(-360 4430);
DISPLAY 0.617021 (-360 4430);
PAINT ORANGE (-360 4430);
FORCEPROP 1 LASTPIN (-350 4250) $PN 2
J 2
(-360 4230);
DISPLAY 0.617021 (-360 4230);
PAINT ORANGE (-360 4230);
FORCEPROP 1 LAST MATERIAL X7R
J 2
(-400 4250);
DISPLAY 0.617021 (-400 4250);
PAINT SKYBLUE (-400 4250);
FORCEPROP 1 LAST VOLTAGE 16V
J 2
(-400 4350);
DISPLAY 0.617021 (-400 4350);
PAINT SKYBLUE (-400 4350);
FORCEPROP 1 LAST PACK_TYPE 0402
J 2
(-400 4150);
DISPLAY 0.617021 (-400 4150);
PAINT SKYBLUE (-400 4150);
FORCEPROP 1 LAST TOLERANCE 10%
J 2
(-400 4300);
DISPLAY 0.617021 (-400 4300);
PAINT SKYBLUE (-400 4300);
FORCEPROP 1 LAST VALUE 0.22UF
J 2
(-400 4400);
DISPLAY 0.617021 (-400 4400);
PAINT SKYBLUE (-400 4400);
FORCEPROP 1 LAST PART_NUMBER A36096-155
J 2
(-400 4200);
DISPLAY 0.617021 (-400 4200);
PAINT BLUE (-400 4200);
FORCEPROP 1 LAST LOCATION C7G9
J 2
(-400 4450);
DISPLAY 0.617021 (-400 4450);
PAINT AQUA (-400 4450);
FORCEPROP 2 LAST ROOM OCP_STEERING
J 2
(-350 4350);
PAINT MONO (-350 4350);
DISPLAY INVISIBLE (-350 4350);
FORCEPROP 1 LAST PATH I21
J 2
(-400 4500);
DISPLAY 0.978723 (-400 4500);
PAINT WHITE (-400 4500);
DISPLAY INVISIBLE (-400 4500);
FORCEPROP 2 LAST CDS_LOCATION C7G9
J 2
(-400 4450);
DISPLAY 0.617021 (-400 4450);
PAINT AQUA (-400 4450);
DISPLAY INVISIBLE (-400 4450);
FORCEPROP 2 LAST SEC 1
J 0
(-400 4550);
DISPLAY 0.680851 (-400 4550);
PAINT MONO (-400 4550);
DISPLAY INVISIBLE (-400 4550);
FORCEPROP 2 LAST CDS_LIB mstr_discrete
J 0
(-350 4350);
PAINT ORANGE (-350 4350);
DISPLAY INVISIBLE (-350 4350);
FORCEPROP 2 LAST SEC_TYPE 0402
J 0
(-400 4550);
DISPLAY 1.021277 (-400 4550);
PAINT ORANGE (-400 4550);
DISPLAY INVISIBLE (-400 4550);
FORCEADD TAP..3
(2200 2575);
FORCEPROP 3 LASTPIN (2200 2525) SIG_NAME P3E_CPU0_PE1_PCH_R_RXP<9>
J 0
(2210 2535);
DISPLAY 0.659574 (2210 2535);
PAINT MONO (2210 2535);
DISPLAY INVISIBLE (2210 2535);
FORCEPROP 1 LASTPIN (2200 2525) BN 9
R 1
J 0
(2193 2513);
DISPLAY 0.617021 (2193 2513);
PAINT GREEN (2193 2513);
FORCEPROP 1 LAST PATH I210
J 0
(2198 2575);
DISPLAY 0.872340 (2198 2575);
PAINT GREEN (2198 2575);
DISPLAY INVISIBLE (2198 2575);
FORCEPROP 2 LAST CDS_LIB mstr_standard
J 0
(2200 2575);
PAINT ORANGE (2200 2575);
DISPLAY INVISIBLE (2200 2575);
FORCEPROP 1 LAST BODY_TYPE PLUMBING
J 0
(2250 2525);
DISPLAY 2.276596 (2250 2525);
PAINT GREEN (2250 2525);
DISPLAY INVISIBLE (2250 2525);
FORCEPROP 1 LAST HDL_TAP TRUE
J 0
(2520 2445);
DISPLAY 2.276596 (2520 2445);
PAINT GREEN (2520 2445);
DISPLAY INVISIBLE (2520 2445);
FORCEADD TAP..3
(2000 2575);
FORCEPROP 3 LASTPIN (2000 2525) SIG_NAME P3E_CPU0_PE1_PCH_R_RXP<10>
J 0
(2010 2535);
DISPLAY 0.659574 (2010 2535);
PAINT MONO (2010 2535);
DISPLAY INVISIBLE (2010 2535);
FORCEPROP 1 LASTPIN (2000 2525) BN 10
R 1
J 0
(1993 2513);
DISPLAY 0.617021 (1993 2513);
PAINT GREEN (1993 2513);
FORCEPROP 1 LAST PATH I211
J 0
(1998 2575);
DISPLAY 0.872340 (1998 2575);
PAINT GREEN (1998 2575);
DISPLAY INVISIBLE (1998 2575);
FORCEPROP 2 LAST CDS_LIB mstr_standard
J 0
(2000 2575);
PAINT ORANGE (2000 2575);
DISPLAY INVISIBLE (2000 2575);
FORCEPROP 1 LAST BODY_TYPE PLUMBING
J 0
(2050 2525);
DISPLAY 2.276596 (2050 2525);
PAINT GREEN (2050 2525);
DISPLAY INVISIBLE (2050 2525);
FORCEPROP 1 LAST HDL_TAP TRUE
J 0
(2320 2445);
DISPLAY 2.276596 (2320 2445);
PAINT GREEN (2320 2445);
DISPLAY INVISIBLE (2320 2445);
FORCEADD CAP..1
R 2
(2000 2325);
FORCEPROP 0 LAST GROUP PCIE_UPLINK
J 0
(1850 2575);
DISPLAY 0.638298 (1850 2575);
PAINT BROWN (1850 2575);
DISPLAY BOTH (1850 2575);
FORCEPROP 1 LAST VALUE 0.22UF
J 2
(1950 2375);
DISPLAY 0.617021 (1950 2375);
PAINT SKYBLUE (1950 2375);
FORCEPROP 1 LAST MATERIAL X7R
J 2
(1950 2225);
DISPLAY 0.617021 (1950 2225);
PAINT SKYBLUE (1950 2225);
FORCEPROP 1 LAST PART_NUMBER A36096-155
J 2
(1950 2175);
DISPLAY 0.617021 (1950 2175);
PAINT BLUE (1950 2175);
FORCEPROP 1 LAST PACK_TYPE 0402
J 2
(1950 2125);
DISPLAY 0.617021 (1950 2125);
PAINT SKYBLUE (1950 2125);
FORCEPROP 1 LASTPIN (2000 2425) $PN 1
J 2
(1990 2405);
DISPLAY 0.617021 (1990 2405);
PAINT ORANGE (1990 2405);
FORCEPROP 1 LASTPIN (2000 2225) $PN 2
J 2
(1990 2205);
DISPLAY 0.617021 (1990 2205);
PAINT ORANGE (1990 2205);
FORCEPROP 1 LAST VOLTAGE 16V
J 2
(1950 2325);
DISPLAY 0.617021 (1950 2325);
PAINT SKYBLUE (1950 2325);
FORCEPROP 1 LAST TOLERANCE 10%
J 2
(1950 2275);
DISPLAY 0.617021 (1950 2275);
PAINT SKYBLUE (1950 2275);
FORCEPROP 1 LAST LOCATION C3M28
J 2
(1950 2425);
DISPLAY 0.617021 (1950 2425);
PAINT AQUA (1950 2425);
FORCEPROP 2 LAST ROOM OCP_STEERING
J 2
(2000 2325);
PAINT MONO (2000 2325);
DISPLAY INVISIBLE (2000 2325);
FORCEPROP 1 LAST PATH I212
J 2
(1950 2475);
DISPLAY 0.978723 (1950 2475);
PAINT WHITE (1950 2475);
DISPLAY INVISIBLE (1950 2475);
FORCEPROP 2 LAST CDS_LOCATION C3M28
J 2
(1950 2425);
DISPLAY 0.617021 (1950 2425);
PAINT AQUA (1950 2425);
DISPLAY INVISIBLE (1950 2425);
FORCEPROP 2 LAST $SEC 1
J 0
(1950 2525);
DISPLAY 0.680851 (1950 2525);
PAINT MONO (1950 2525);
DISPLAY INVISIBLE (1950 2525);
FORCEPROP 2 LAST CDS_SEC 1
J 0
(1950 2525);
DISPLAY 1.021277 (1950 2525);
PAINT ORANGE (1950 2525);
DISPLAY INVISIBLE (1950 2525);
FORCEPROP 2 LAST CDS_LIB mstr_discrete
J 0
(2000 2325);
PAINT ORANGE (2000 2325);
DISPLAY INVISIBLE (2000 2325);
FORCEADD TAP..3
(1800 2575);
FORCEPROP 3 LASTPIN (1800 2525) SIG_NAME P3E_CPU0_PE1_PCH_R_RXP<11>
J 0
(1810 2535);
DISPLAY 0.659574 (1810 2535);
PAINT MONO (1810 2535);
DISPLAY INVISIBLE (1810 2535);
FORCEPROP 1 LASTPIN (1800 2525) BN 11
R 1
J 0
(1793 2513);
DISPLAY 0.617021 (1793 2513);
PAINT GREEN (1793 2513);
FORCEPROP 1 LAST PATH I213
J 0
(1798 2575);
DISPLAY 0.872340 (1798 2575);
PAINT GREEN (1798 2575);
DISPLAY INVISIBLE (1798 2575);
FORCEPROP 2 LAST CDS_LIB mstr_standard
J 0
(1800 2575);
PAINT ORANGE (1800 2575);
DISPLAY INVISIBLE (1800 2575);
FORCEPROP 1 LAST BODY_TYPE PLUMBING
J 0
(1850 2525);
DISPLAY 2.276596 (1850 2525);
PAINT GREEN (1850 2525);
DISPLAY INVISIBLE (1850 2525);
FORCEPROP 1 LAST HDL_TAP TRUE
J 0
(2120 2445);
DISPLAY 2.276596 (2120 2445);
PAINT GREEN (2120 2445);
DISPLAY INVISIBLE (2120 2445);
FORCEADD TAP..7
(2400 1775);
FORCEPROP 3 LASTPIN (2400 1825) SIG_NAME P3E_CPU0_PE1_PCH_RXP<8>
J 0
(2410 1835);
DISPLAY 0.659574 (2410 1835);
PAINT MONO (2410 1835);
DISPLAY INVISIBLE (2410 1835);
FORCEPROP 1 LASTPIN (2400 1825) BN 8
R 1
J 0
(2393 1773);
DISPLAY 0.617021 (2393 1773);
PAINT GREEN (2393 1773);
FORCEPROP 1 LAST PATH I214
J 0
(2398 1775);
DISPLAY 0.872340 (2398 1775);
PAINT GREEN (2398 1775);
DISPLAY INVISIBLE (2398 1775);
FORCEPROP 2 LAST CDS_LIB mstr_standard
J 0
(2400 1775);
PAINT ORANGE (2400 1775);
DISPLAY INVISIBLE (2400 1775);
FORCEPROP 1 LAST BODY_TYPE PLUMBING
J 0
(2450 1775);
DISPLAY 2.276596 (2450 1775);
PAINT GREEN (2450 1775);
DISPLAY INVISIBLE (2450 1775);
FORCEPROP 1 LAST HDL_TAP TRUE
J 0
(2720 1645);
DISPLAY 2.276596 (2720 1645);
PAINT GREEN (2720 1645);
DISPLAY INVISIBLE (2720 1645);
FORCEADD TAP..3
(2450 1575);
FORCEPROP 3 LASTPIN (2450 1525) SIG_NAME P3E_CPU0_PE1_PCH_R_RXN<8>
J 0
(2460 1535);
DISPLAY 0.659574 (2460 1535);
PAINT MONO (2460 1535);
DISPLAY INVISIBLE (2460 1535);
FORCEPROP 1 LASTPIN (2450 1525) BN 8
R 1
J 0
(2443 1513);
DISPLAY 0.617021 (2443 1513);
PAINT GREEN (2443 1513);
FORCEPROP 1 LAST PATH I215
J 0
(2448 1575);
DISPLAY 0.872340 (2448 1575);
PAINT GREEN (2448 1575);
DISPLAY INVISIBLE (2448 1575);
FORCEPROP 2 LAST CDS_LIB mstr_standard
J 0
(2450 1575);
PAINT ORANGE (2450 1575);
DISPLAY INVISIBLE (2450 1575);
FORCEPROP 1 LAST BODY_TYPE PLUMBING
J 0
(2500 1525);
DISPLAY 2.276596 (2500 1525);
PAINT GREEN (2500 1525);
DISPLAY INVISIBLE (2500 1525);
FORCEPROP 1 LAST HDL_TAP TRUE
J 0
(2770 1445);
DISPLAY 2.276596 (2770 1445);
PAINT GREEN (2770 1445);
DISPLAY INVISIBLE (2770 1445);
FORCEADD TAP..3
(2250 1575);
FORCEPROP 3 LASTPIN (2250 1525) SIG_NAME P3E_CPU0_PE1_PCH_R_RXN<9>
J 0
(2260 1535);
DISPLAY 0.659574 (2260 1535);
PAINT MONO (2260 1535);
DISPLAY INVISIBLE (2260 1535);
FORCEPROP 1 LASTPIN (2250 1525) BN 9
R 1
J 0
(2243 1513);
DISPLAY 0.617021 (2243 1513);
PAINT GREEN (2243 1513);
FORCEPROP 1 LAST PATH I216
J 0
(2248 1575);
DISPLAY 0.872340 (2248 1575);
PAINT GREEN (2248 1575);
DISPLAY INVISIBLE (2248 1575);
FORCEPROP 2 LAST CDS_LIB mstr_standard
J 0
(2250 1575);
PAINT ORANGE (2250 1575);
DISPLAY INVISIBLE (2250 1575);
FORCEPROP 1 LAST BODY_TYPE PLUMBING
J 0
(2300 1525);
DISPLAY 2.276596 (2300 1525);
PAINT GREEN (2300 1525);
DISPLAY INVISIBLE (2300 1525);
FORCEPROP 1 LAST HDL_TAP TRUE
J 0
(2570 1445);
DISPLAY 2.276596 (2570 1445);
PAINT GREEN (2570 1445);
DISPLAY INVISIBLE (2570 1445);
FORCEADD CAP..1
R 2
(2450 1325);
FORCEPROP 1 LAST TOLERANCE 10%
J 2
(2400 1275);
DISPLAY 0.617021 (2400 1275);
PAINT SKYBLUE (2400 1275);
FORCEPROP 1 LAST MATERIAL X7R
J 2
(2400 1225);
DISPLAY 0.617021 (2400 1225);
PAINT SKYBLUE (2400 1225);
FORCEPROP 1 LAST VALUE 0.22UF
J 2
(2400 1375);
DISPLAY 0.617021 (2400 1375);
PAINT SKYBLUE (2400 1375);
FORCEPROP 1 LASTPIN (2450 1425) $PN 1
J 2
(2440 1405);
DISPLAY 0.617021 (2440 1405);
PAINT ORANGE (2440 1405);
FORCEPROP 1 LAST VOLTAGE 16V
J 2
(2400 1325);
DISPLAY 0.617021 (2400 1325);
PAINT SKYBLUE (2400 1325);
FORCEPROP 1 LAST LOCATION C3M33
J 2
(2400 1425);
DISPLAY 0.617021 (2400 1425);
PAINT AQUA (2400 1425);
FORCEPROP 1 LASTPIN (2450 1225) $PN 2
J 2
(2440 1205);
DISPLAY 0.617021 (2440 1205);
PAINT ORANGE (2440 1205);
FORCEPROP 1 LAST PART_NUMBER A36096-155
J 2
(2400 1175);
DISPLAY 0.617021 (2400 1175);
PAINT BLUE (2400 1175);
FORCEPROP 1 LAST PACK_TYPE 0402
J 2
(2400 1125);
DISPLAY 0.617021 (2400 1125);
PAINT SKYBLUE (2400 1125);
FORCEPROP 0 LAST GROUP PCIE_UPLINK
J 0
(2300 1475);
DISPLAY 0.638298 (2300 1475);
PAINT BROWN (2300 1475);
DISPLAY BOTH (2300 1475);
FORCEPROP 2 LAST ROOM OCP_STEERING
J 2
(2450 1325);
PAINT MONO (2450 1325);
DISPLAY INVISIBLE (2450 1325);
FORCEPROP 1 LAST PATH I217
J 2
(2400 1475);
DISPLAY 0.978723 (2400 1475);
PAINT WHITE (2400 1475);
DISPLAY INVISIBLE (2400 1475);
FORCEPROP 2 LAST CDS_LOCATION C3M33
J 2
(2400 1425);
DISPLAY 0.617021 (2400 1425);
PAINT AQUA (2400 1425);
DISPLAY INVISIBLE (2400 1425);
FORCEPROP 2 LAST $SEC 1
J 0
(2400 1525);
DISPLAY 0.680851 (2400 1525);
PAINT MONO (2400 1525);
DISPLAY INVISIBLE (2400 1525);
FORCEPROP 2 LAST CDS_SEC 1
J 0
(2400 1525);
DISPLAY 1.021277 (2400 1525);
PAINT ORANGE (2400 1525);
DISPLAY INVISIBLE (2400 1525);
FORCEPROP 2 LAST CDS_LIB mstr_discrete
J 0
(2450 1325);
PAINT ORANGE (2450 1325);
DISPLAY INVISIBLE (2450 1325);
FORCEADD CAP..1
R 2
(2200 2025);
FORCEPROP 1 LAST VALUE 0.22UF
J 2
(2150 2075);
DISPLAY 0.617021 (2150 2075);
PAINT SKYBLUE (2150 2075);
FORCEPROP 1 LAST TOLERANCE 10%
J 2
(2150 1975);
DISPLAY 0.617021 (2150 1975);
PAINT SKYBLUE (2150 1975);
FORCEPROP 1 LASTPIN (2200 2125) $PN 1
J 2
(2190 2105);
DISPLAY 0.617021 (2190 2105);
PAINT ORANGE (2190 2105);
FORCEPROP 1 LASTPIN (2200 1925) $PN 2
J 2
(2190 1905);
DISPLAY 0.617021 (2190 1905);
PAINT ORANGE (2190 1905);
FORCEPROP 1 LAST MATERIAL X7R
J 2
(2150 1925);
DISPLAY 0.617021 (2150 1925);
PAINT SKYBLUE (2150 1925);
FORCEPROP 1 LAST VOLTAGE 16V
J 2
(2150 2025);
DISPLAY 0.617021 (2150 2025);
PAINT SKYBLUE (2150 2025);
FORCEPROP 1 LAST PART_NUMBER A36096-155
J 2
(2150 1875);
DISPLAY 0.617021 (2150 1875);
PAINT BLUE (2150 1875);
FORCEPROP 1 LAST LOCATION C3M36
J 2
(2150 2125);
DISPLAY 0.617021 (2150 2125);
PAINT AQUA (2150 2125);
FORCEPROP 1 LAST PACK_TYPE 0402
J 2
(2150 1825);
DISPLAY 0.617021 (2150 1825);
PAINT SKYBLUE (2150 1825);
FORCEPROP 0 LAST GROUP PCIE_UPLINK
J 0
(2050 1750);
DISPLAY 0.638298 (2050 1750);
PAINT BROWN (2050 1750);
DISPLAY BOTH (2050 1750);
FORCEPROP 2 LAST ROOM OCP_STEERING
J 2
(2200 2025);
PAINT MONO (2200 2025);
DISPLAY INVISIBLE (2200 2025);
FORCEPROP 1 LAST PATH I218
J 2
(2150 2175);
DISPLAY 0.978723 (2150 2175);
PAINT WHITE (2150 2175);
DISPLAY INVISIBLE (2150 2175);
FORCEPROP 2 LAST CDS_LOCATION C3M36
J 2
(2150 2125);
DISPLAY 0.617021 (2150 2125);
PAINT AQUA (2150 2125);
DISPLAY INVISIBLE (2150 2125);
FORCEPROP 2 LAST $SEC 1
J 0
(2150 2225);
DISPLAY 0.680851 (2150 2225);
PAINT MONO (2150 2225);
DISPLAY INVISIBLE (2150 2225);
FORCEPROP 2 LAST CDS_SEC 1
J 0
(2150 2225);
DISPLAY 1.021277 (2150 2225);
PAINT ORANGE (2150 2225);
DISPLAY INVISIBLE (2150 2225);
FORCEPROP 2 LAST CDS_LIB mstr_discrete
J 0
(2200 2025);
PAINT ORANGE (2200 2025);
DISPLAY INVISIBLE (2200 2025);
FORCEADD TAP..7
(2200 1775);
FORCEPROP 3 LASTPIN (2200 1825) SIG_NAME P3E_CPU0_PE1_PCH_RXP<9>
J 0
(2210 1835);
DISPLAY 0.659574 (2210 1835);
PAINT MONO (2210 1835);
DISPLAY INVISIBLE (2210 1835);
FORCEPROP 1 LASTPIN (2200 1825) BN 9
R 1
J 0
(2193 1773);
DISPLAY 0.617021 (2193 1773);
PAINT GREEN (2193 1773);
FORCEPROP 1 LAST PATH I219
J 0
(2198 1775);
DISPLAY 0.872340 (2198 1775);
PAINT GREEN (2198 1775);
DISPLAY INVISIBLE (2198 1775);
FORCEPROP 2 LAST CDS_LIB mstr_standard
J 0
(2200 1775);
PAINT ORANGE (2200 1775);
DISPLAY INVISIBLE (2200 1775);
FORCEPROP 1 LAST BODY_TYPE PLUMBING
J 0
(2250 1775);
DISPLAY 2.276596 (2250 1775);
PAINT GREEN (2250 1775);
DISPLAY INVISIBLE (2250 1775);
FORCEPROP 1 LAST HDL_TAP TRUE
J 0
(2520 1645);
DISPLAY 2.276596 (2520 1645);
PAINT GREEN (2520 1645);
DISPLAY INVISIBLE (2520 1645);
FORCEADD CAP..1
R 2
(-550 4650);
FORCEPROP 1 LASTPIN (-550 4750) $PN 1
J 2
(-560 4730);
DISPLAY 0.617021 (-560 4730);
PAINT ORANGE (-560 4730);
FORCEPROP 1 LASTPIN (-550 4550) $PN 2
J 2
(-560 4530);
DISPLAY 0.617021 (-560 4530);
PAINT ORANGE (-560 4530);
FORCEPROP 1 LAST MATERIAL X7R
J 2
(-600 4550);
DISPLAY 0.617021 (-600 4550);
PAINT SKYBLUE (-600 4550);
FORCEPROP 1 LAST VOLTAGE 16V
J 2
(-600 4650);
DISPLAY 0.617021 (-600 4650);
PAINT SKYBLUE (-600 4650);
FORCEPROP 1 LAST PACK_TYPE 0402
J 2
(-600 4450);
DISPLAY 0.617021 (-600 4450);
PAINT SKYBLUE (-600 4450);
FORCEPROP 1 LAST TOLERANCE 10%
J 2
(-600 4600);
DISPLAY 0.617021 (-600 4600);
PAINT SKYBLUE (-600 4600);
FORCEPROP 1 LAST VALUE 0.22UF
J 2
(-600 4700);
DISPLAY 0.617021 (-600 4700);
PAINT SKYBLUE (-600 4700);
FORCEPROP 1 LAST PART_NUMBER A36096-155
J 2
(-600 4500);
DISPLAY 0.617021 (-600 4500);
PAINT BLUE (-600 4500);
FORCEPROP 1 LAST LOCATION C7G8
J 2
(-600 4750);
DISPLAY 0.617021 (-600 4750);
PAINT AQUA (-600 4750);
FORCEPROP 2 LAST ROOM OCP_STEERING
J 2
(-550 4650);
PAINT MONO (-550 4650);
DISPLAY INVISIBLE (-550 4650);
FORCEPROP 1 LAST PATH I22
J 2
(-600 4800);
DISPLAY 0.978723 (-600 4800);
PAINT WHITE (-600 4800);
DISPLAY INVISIBLE (-600 4800);
FORCEPROP 2 LAST CDS_LOCATION C7G8
J 2
(-600 4750);
DISPLAY 0.617021 (-600 4750);
PAINT AQUA (-600 4750);
DISPLAY INVISIBLE (-600 4750);
FORCEPROP 2 LAST SEC 1
J 0
(-600 4850);
DISPLAY 0.680851 (-600 4850);
PAINT MONO (-600 4850);
DISPLAY INVISIBLE (-600 4850);
FORCEPROP 2 LAST CDS_LIB mstr_discrete
J 0
(-550 4650);
PAINT ORANGE (-550 4650);
DISPLAY INVISIBLE (-550 4650);
FORCEPROP 2 LAST SEC_TYPE 0402
J 0
(-600 4850);
DISPLAY 1.021277 (-600 4850);
PAINT ORANGE (-600 4850);
DISPLAY INVISIBLE (-600 4850);
FORCEADD TAP..7
(2000 1775);
FORCEPROP 3 LASTPIN (2000 1825) SIG_NAME P3E_CPU0_PE1_PCH_RXP<10>
J 0
(2010 1835);
DISPLAY 0.659574 (2010 1835);
PAINT MONO (2010 1835);
DISPLAY INVISIBLE (2010 1835);
FORCEPROP 1 LASTPIN (2000 1825) BN 10
R 1
J 0
(1993 1773);
DISPLAY 0.617021 (1993 1773);
PAINT GREEN (1993 1773);
FORCEPROP 1 LAST PATH I220
J 0
(1998 1775);
DISPLAY 0.872340 (1998 1775);
PAINT GREEN (1998 1775);
DISPLAY INVISIBLE (1998 1775);
FORCEPROP 2 LAST CDS_LIB mstr_standard
J 0
(2000 1775);
PAINT ORANGE (2000 1775);
DISPLAY INVISIBLE (2000 1775);
FORCEPROP 1 LAST BODY_TYPE PLUMBING
J 0
(2050 1775);
DISPLAY 2.276596 (2050 1775);
PAINT GREEN (2050 1775);
DISPLAY INVISIBLE (2050 1775);
FORCEPROP 1 LAST HDL_TAP TRUE
J 0
(2320 1645);
DISPLAY 2.276596 (2320 1645);
PAINT GREEN (2320 1645);
DISPLAY INVISIBLE (2320 1645);
FORCEADD TAP..7
(1800 1775);
FORCEPROP 3 LASTPIN (1800 1825) SIG_NAME P3E_CPU0_PE1_PCH_RXP<11>
J 0
(1810 1835);
DISPLAY 0.659574 (1810 1835);
PAINT MONO (1810 1835);
DISPLAY INVISIBLE (1810 1835);
FORCEPROP 1 LASTPIN (1800 1825) BN 11
R 1
J 0
(1793 1773);
DISPLAY 0.617021 (1793 1773);
PAINT GREEN (1793 1773);
FORCEPROP 1 LAST PATH I221
J 0
(1798 1775);
DISPLAY 0.872340 (1798 1775);
PAINT GREEN (1798 1775);
DISPLAY INVISIBLE (1798 1775);
FORCEPROP 2 LAST CDS_LIB mstr_standard
J 0
(1800 1775);
PAINT ORANGE (1800 1775);
DISPLAY INVISIBLE (1800 1775);
FORCEPROP 1 LAST BODY_TYPE PLUMBING
J 0
(1850 1775);
DISPLAY 2.276596 (1850 1775);
PAINT GREEN (1850 1775);
DISPLAY INVISIBLE (1850 1775);
FORCEPROP 1 LAST HDL_TAP TRUE
J 0
(2120 1645);
DISPLAY 2.276596 (2120 1645);
PAINT GREEN (2120 1645);
DISPLAY INVISIBLE (2120 1645);
FORCEADD TAP..3
(2050 1575);
FORCEPROP 3 LASTPIN (2050 1525) SIG_NAME P3E_CPU0_PE1_PCH_R_RXN<10>
J 0
(2060 1535);
DISPLAY 0.659574 (2060 1535);
PAINT MONO (2060 1535);
DISPLAY INVISIBLE (2060 1535);
FORCEPROP 1 LASTPIN (2050 1525) BN 10
R 1
J 0
(2043 1513);
DISPLAY 0.617021 (2043 1513);
PAINT GREEN (2043 1513);
FORCEPROP 1 LAST PATH I222
J 0
(2048 1575);
DISPLAY 0.872340 (2048 1575);
PAINT GREEN (2048 1575);
DISPLAY INVISIBLE (2048 1575);
FORCEPROP 2 LAST CDS_LIB mstr_standard
J 0
(2050 1575);
PAINT ORANGE (2050 1575);
DISPLAY INVISIBLE (2050 1575);
FORCEPROP 1 LAST BODY_TYPE PLUMBING
J 0
(2100 1525);
DISPLAY 2.276596 (2100 1525);
PAINT GREEN (2100 1525);
DISPLAY INVISIBLE (2100 1525);
FORCEPROP 1 LAST HDL_TAP TRUE
J 0
(2370 1445);
DISPLAY 2.276596 (2370 1445);
PAINT GREEN (2370 1445);
DISPLAY INVISIBLE (2370 1445);
FORCEADD CAP..1
R 2
(2050 1325);
FORCEPROP 1 LAST TOLERANCE 10%
J 2
(2000 1275);
DISPLAY 0.617021 (2000 1275);
PAINT SKYBLUE (2000 1275);
FORCEPROP 1 LAST LOCATION C3M32
J 2
(2000 1425);
DISPLAY 0.617021 (2000 1425);
PAINT AQUA (2000 1425);
FORCEPROP 1 LASTPIN (2050 1425) $PN 1
J 2
(2040 1405);
DISPLAY 0.617021 (2040 1405);
PAINT ORANGE (2040 1405);
FORCEPROP 1 LASTPIN (2050 1225) $PN 2
J 2
(2040 1205);
DISPLAY 0.617021 (2040 1205);
PAINT ORANGE (2040 1205);
FORCEPROP 1 LAST MATERIAL X7R
J 2
(2000 1225);
DISPLAY 0.617021 (2000 1225);
PAINT SKYBLUE (2000 1225);
FORCEPROP 1 LAST VOLTAGE 16V
J 2
(2000 1325);
DISPLAY 0.617021 (2000 1325);
PAINT SKYBLUE (2000 1325);
FORCEPROP 1 LAST PACK_TYPE 0402
J 2
(2000 1125);
DISPLAY 0.617021 (2000 1125);
PAINT SKYBLUE (2000 1125);
FORCEPROP 1 LAST VALUE 0.22UF
J 2
(2000 1375);
DISPLAY 0.617021 (2000 1375);
PAINT SKYBLUE (2000 1375);
FORCEPROP 1 LAST PART_NUMBER A36096-155
J 2
(2000 1175);
DISPLAY 0.617021 (2000 1175);
PAINT BLUE (2000 1175);
FORCEPROP 0 LAST GROUP PCIE_UPLINK
J 0
(1875 1475);
DISPLAY 0.638298 (1875 1475);
PAINT BROWN (1875 1475);
DISPLAY BOTH (1875 1475);
FORCEPROP 2 LAST ROOM OCP_STEERING
J 2
(2050 1325);
PAINT MONO (2050 1325);
DISPLAY INVISIBLE (2050 1325);
FORCEPROP 1 LAST PATH I223
J 2
(2000 1475);
DISPLAY 0.978723 (2000 1475);
PAINT WHITE (2000 1475);
DISPLAY INVISIBLE (2000 1475);
FORCEPROP 2 LAST CDS_LOCATION C3M32
J 2
(2000 1425);
DISPLAY 0.617021 (2000 1425);
PAINT AQUA (2000 1425);
DISPLAY INVISIBLE (2000 1425);
FORCEPROP 2 LAST $SEC 1
J 0
(2000 1525);
DISPLAY 0.680851 (2000 1525);
PAINT MONO (2000 1525);
DISPLAY INVISIBLE (2000 1525);
FORCEPROP 2 LAST CDS_SEC 1
J 0
(2000 1525);
DISPLAY 1.021277 (2000 1525);
PAINT ORANGE (2000 1525);
DISPLAY INVISIBLE (2000 1525);
FORCEPROP 2 LAST CDS_LIB mstr_discrete
J 0
(2050 1325);
PAINT ORANGE (2050 1325);
DISPLAY INVISIBLE (2050 1325);
FORCEADD TAP..3
(1850 1575);
FORCEPROP 3 LASTPIN (1850 1525) SIG_NAME P3E_CPU0_PE1_PCH_R_RXN<11>
J 0
(1860 1535);
DISPLAY 0.659574 (1860 1535);
PAINT MONO (1860 1535);
DISPLAY INVISIBLE (1860 1535);
FORCEPROP 1 LASTPIN (1850 1525) BN 11
R 1
J 0
(1843 1513);
DISPLAY 0.617021 (1843 1513);
PAINT GREEN (1843 1513);
FORCEPROP 1 LAST PATH I224
J 0
(1848 1575);
DISPLAY 0.872340 (1848 1575);
PAINT GREEN (1848 1575);
DISPLAY INVISIBLE (1848 1575);
FORCEPROP 2 LAST CDS_LIB mstr_standard
J 0
(1850 1575);
PAINT ORANGE (1850 1575);
DISPLAY INVISIBLE (1850 1575);
FORCEPROP 1 LAST BODY_TYPE PLUMBING
J 0
(1900 1525);
DISPLAY 2.276596 (1900 1525);
PAINT GREEN (1900 1525);
DISPLAY INVISIBLE (1900 1525);
FORCEPROP 1 LAST HDL_TAP TRUE
J 0
(2170 1445);
DISPLAY 2.276596 (2170 1445);
PAINT GREEN (2170 1445);
DISPLAY INVISIBLE (2170 1445);
FORCEADD CAP..1
R 2
(2250 1025);
FORCEPROP 1 LAST PART_NUMBER A36096-155
J 2
(2200 875);
DISPLAY 0.617021 (2200 875);
PAINT BLUE (2200 875);
FORCEPROP 1 LAST PACK_TYPE 0402
J 2
(2200 825);
DISPLAY 0.617021 (2200 825);
PAINT SKYBLUE (2200 825);
FORCEPROP 1 LAST TOLERANCE 10%
J 2
(2200 975);
DISPLAY 0.617021 (2200 975);
PAINT SKYBLUE (2200 975);
FORCEPROP 1 LASTPIN (2250 1125) $PN 1
J 2
(2240 1105);
DISPLAY 0.617021 (2240 1105);
PAINT ORANGE (2240 1105);
FORCEPROP 1 LASTPIN (2250 925) $PN 2
J 2
(2240 905);
DISPLAY 0.617021 (2240 905);
PAINT ORANGE (2240 905);
FORCEPROP 1 LAST MATERIAL X7R
J 2
(2200 925);
DISPLAY 0.617021 (2200 925);
PAINT SKYBLUE (2200 925);
FORCEPROP 1 LAST VOLTAGE 16V
J 2
(2200 1025);
DISPLAY 0.617021 (2200 1025);
PAINT SKYBLUE (2200 1025);
FORCEPROP 1 LAST VALUE 0.22UF
J 2
(2200 1075);
DISPLAY 0.617021 (2200 1075);
PAINT SKYBLUE (2200 1075);
FORCEPROP 1 LAST LOCATION C3M35
J 2
(2200 1125);
DISPLAY 0.617021 (2200 1125);
PAINT AQUA (2200 1125);
FORCEPROP 0 LAST GROUP PCIE_UPLINK
J 0
(2100 725);
DISPLAY 0.638298 (2100 725);
PAINT BROWN (2100 725);
DISPLAY BOTH (2100 725);
FORCEPROP 2 LAST ROOM OCP_STEERING
J 2
(2250 1025);
PAINT MONO (2250 1025);
DISPLAY INVISIBLE (2250 1025);
FORCEPROP 1 LAST PATH I225
J 2
(2200 1175);
DISPLAY 0.978723 (2200 1175);
PAINT WHITE (2200 1175);
DISPLAY INVISIBLE (2200 1175);
FORCEPROP 2 LAST CDS_LOCATION C3M35
J 2
(2200 1125);
DISPLAY 0.617021 (2200 1125);
PAINT AQUA (2200 1125);
DISPLAY INVISIBLE (2200 1125);
FORCEPROP 2 LAST $SEC 1
J 0
(2200 1225);
DISPLAY 0.680851 (2200 1225);
PAINT MONO (2200 1225);
DISPLAY INVISIBLE (2200 1225);
FORCEPROP 2 LAST CDS_SEC 1
J 0
(2200 1225);
DISPLAY 1.021277 (2200 1225);
PAINT ORANGE (2200 1225);
DISPLAY INVISIBLE (2200 1225);
FORCEPROP 2 LAST CDS_LIB mstr_discrete
J 0
(2250 1025);
PAINT ORANGE (2250 1025);
DISPLAY INVISIBLE (2250 1025);
FORCEADD TAP..7
(2250 775);
FORCEPROP 3 LASTPIN (2250 825) SIG_NAME P3E_CPU0_PE1_PCH_RXN<9>
J 0
(2260 835);
DISPLAY 0.659574 (2260 835);
PAINT MONO (2260 835);
DISPLAY INVISIBLE (2260 835);
FORCEPROP 1 LASTPIN (2250 825) BN 9
R 1
J 0
(2243 773);
DISPLAY 0.617021 (2243 773);
PAINT GREEN (2243 773);
FORCEPROP 1 LAST PATH I226
J 0
(2248 775);
DISPLAY 0.872340 (2248 775);
PAINT GREEN (2248 775);
DISPLAY INVISIBLE (2248 775);
FORCEPROP 2 LAST CDS_LIB mstr_standard
J 0
(2250 775);
PAINT ORANGE (2250 775);
DISPLAY INVISIBLE (2250 775);
FORCEPROP 1 LAST BODY_TYPE PLUMBING
J 0
(2300 775);
DISPLAY 2.276596 (2300 775);
PAINT GREEN (2300 775);
DISPLAY INVISIBLE (2300 775);
FORCEPROP 1 LAST HDL_TAP TRUE
J 0
(2570 645);
DISPLAY 2.276596 (2570 645);
PAINT GREEN (2570 645);
DISPLAY INVISIBLE (2570 645);
FORCEADD TAP..7
(2450 775);
FORCEPROP 3 LASTPIN (2450 825) SIG_NAME P3E_CPU0_PE1_PCH_RXN<8>
J 0
(2460 835);
DISPLAY 0.659574 (2460 835);
PAINT MONO (2460 835);
DISPLAY INVISIBLE (2460 835);
FORCEPROP 1 LASTPIN (2450 825) BN 8
R 1
J 0
(2443 773);
DISPLAY 0.617021 (2443 773);
PAINT GREEN (2443 773);
FORCEPROP 1 LAST PATH I227
J 0
(2448 775);
DISPLAY 0.872340 (2448 775);
PAINT GREEN (2448 775);
DISPLAY INVISIBLE (2448 775);
FORCEPROP 2 LAST CDS_LIB mstr_standard
J 0
(2450 775);
PAINT ORANGE (2450 775);
DISPLAY INVISIBLE (2450 775);
FORCEPROP 1 LAST BODY_TYPE PLUMBING
J 0
(2500 775);
DISPLAY 2.276596 (2500 775);
PAINT GREEN (2500 775);
DISPLAY INVISIBLE (2500 775);
FORCEPROP 1 LAST HDL_TAP TRUE
J 0
(2770 645);
DISPLAY 2.276596 (2770 645);
PAINT GREEN (2770 645);
DISPLAY INVISIBLE (2770 645);
FORCEADD TAP..7
(2050 775);
FORCEPROP 3 LASTPIN (2050 825) SIG_NAME P3E_CPU0_PE1_PCH_RXN<10>
J 0
(2060 835);
DISPLAY 0.659574 (2060 835);
PAINT MONO (2060 835);
DISPLAY INVISIBLE (2060 835);
FORCEPROP 1 LASTPIN (2050 825) BN 10
R 1
J 0
(2043 773);
DISPLAY 0.617021 (2043 773);
PAINT GREEN (2043 773);
FORCEPROP 1 LAST PATH I228
J 0
(2048 775);
DISPLAY 0.872340 (2048 775);
PAINT GREEN (2048 775);
DISPLAY INVISIBLE (2048 775);
FORCEPROP 2 LAST CDS_LIB mstr_standard
J 0
(2050 775);
PAINT ORANGE (2050 775);
DISPLAY INVISIBLE (2050 775);
FORCEPROP 1 LAST BODY_TYPE PLUMBING
J 0
(2100 775);
DISPLAY 2.276596 (2100 775);
PAINT GREEN (2100 775);
DISPLAY INVISIBLE (2100 775);
FORCEPROP 1 LAST HDL_TAP TRUE
J 0
(2370 645);
DISPLAY 2.276596 (2370 645);
PAINT GREEN (2370 645);
DISPLAY INVISIBLE (2370 645);
FORCEADD CAP..1
R 2
(1850 1025);
FORCEPROP 1 LAST VALUE 0.22UF
J 2
(1800 1075);
DISPLAY 0.617021 (1800 1075);
PAINT SKYBLUE (1800 1075);
FORCEPROP 1 LAST TOLERANCE 10%
J 2
(1800 975);
DISPLAY 0.617021 (1800 975);
PAINT SKYBLUE (1800 975);
FORCEPROP 1 LAST MATERIAL X7R
J 2
(1800 925);
DISPLAY 0.617021 (1800 925);
PAINT SKYBLUE (1800 925);
FORCEPROP 1 LASTPIN (1850 1125) $PN 1
J 2
(1840 1105);
DISPLAY 0.617021 (1840 1105);
PAINT ORANGE (1840 1105);
FORCEPROP 1 LASTPIN (1850 925) $PN 2
J 2
(1840 905);
DISPLAY 0.617021 (1840 905);
PAINT ORANGE (1840 905);
FORCEPROP 1 LAST VOLTAGE 16V
J 2
(1800 1025);
DISPLAY 0.617021 (1800 1025);
PAINT SKYBLUE (1800 1025);
FORCEPROP 1 LAST PACK_TYPE 0402
J 2
(1800 825);
DISPLAY 0.617021 (1800 825);
PAINT SKYBLUE (1800 825);
FORCEPROP 1 LAST PART_NUMBER A36096-155
J 2
(1800 875);
DISPLAY 0.617021 (1800 875);
PAINT BLUE (1800 875);
FORCEPROP 1 LAST LOCATION C3M26
J 2
(1800 1125);
DISPLAY 0.617021 (1800 1125);
PAINT AQUA (1800 1125);
FORCEPROP 0 LAST GROUP PCIE_UPLINK
J 0
(1700 750);
DISPLAY 0.638298 (1700 750);
PAINT BROWN (1700 750);
DISPLAY BOTH (1700 750);
FORCEPROP 2 LAST ROOM OCP_STEERING
J 2
(1850 1025);
PAINT MONO (1850 1025);
DISPLAY INVISIBLE (1850 1025);
FORCEPROP 1 LAST PATH I229
J 2
(1800 1175);
DISPLAY 0.978723 (1800 1175);
PAINT WHITE (1800 1175);
DISPLAY INVISIBLE (1800 1175);
FORCEPROP 2 LAST CDS_LOCATION C3M26
J 2
(1800 1125);
DISPLAY 0.617021 (1800 1125);
PAINT AQUA (1800 1125);
DISPLAY INVISIBLE (1800 1125);
FORCEPROP 2 LAST $SEC 1
J 0
(1800 1225);
DISPLAY 0.680851 (1800 1225);
PAINT MONO (1800 1225);
DISPLAY INVISIBLE (1800 1225);
FORCEPROP 2 LAST CDS_SEC 1
J 0
(1800 1225);
DISPLAY 1.021277 (1800 1225);
PAINT ORANGE (1800 1225);
DISPLAY INVISIBLE (1800 1225);
FORCEPROP 2 LAST CDS_LIB mstr_discrete
J 0
(1850 1025);
PAINT ORANGE (1850 1025);
DISPLAY INVISIBLE (1850 1025);
FORCEADD TAP..3
(-100 3900);
FORCEPROP 3 LASTPIN (-100 3850) SIG_NAME P3E_CPU0_PE2_SS_TXN<12>
J 0
(-90 3860);
DISPLAY 0.659574 (-90 3860);
PAINT MONO (-90 3860);
DISPLAY INVISIBLE (-90 3860);
FORCEPROP 1 LASTPIN (-100 3850) BN 12
R 1
J 0
(-107 3838);
DISPLAY 0.617021 (-107 3838);
PAINT GREEN (-107 3838);
FORCEPROP 1 LAST PATH I23
J 0
(-102 3900);
DISPLAY 0.872340 (-102 3900);
PAINT GREEN (-102 3900);
DISPLAY INVISIBLE (-102 3900);
FORCEPROP 2 LAST CDS_LIB mstr_standard
J 0
(-100 3900);
PAINT ORANGE (-100 3900);
DISPLAY INVISIBLE (-100 3900);
FORCEPROP 1 LAST BODY_TYPE PLUMBING
J 0
(-50 3850);
DISPLAY 2.276596 (-50 3850);
PAINT GREEN (-50 3850);
DISPLAY INVISIBLE (-50 3850);
FORCEPROP 1 LAST HDL_TAP TRUE
J 0
(220 3770);
DISPLAY 2.276596 (220 3770);
PAINT GREEN (220 3770);
DISPLAY INVISIBLE (220 3770);
FORCEADD TAP..7
(1850 775);
FORCEPROP 3 LASTPIN (1850 825) SIG_NAME P3E_CPU0_PE1_PCH_RXN<11>
J 0
(1860 835);
DISPLAY 0.659574 (1860 835);
PAINT MONO (1860 835);
DISPLAY INVISIBLE (1860 835);
FORCEPROP 1 LASTPIN (1850 825) BN 11
R 1
J 0
(1843 773);
DISPLAY 0.617021 (1843 773);
PAINT GREEN (1843 773);
FORCEPROP 1 LAST PATH I230
J 0
(1848 775);
DISPLAY 0.872340 (1848 775);
PAINT GREEN (1848 775);
DISPLAY INVISIBLE (1848 775);
FORCEPROP 2 LAST CDS_LIB mstr_standard
J 0
(1850 775);
PAINT ORANGE (1850 775);
DISPLAY INVISIBLE (1850 775);
FORCEPROP 1 LAST BODY_TYPE PLUMBING
J 0
(1900 775);
DISPLAY 2.276596 (1900 775);
PAINT GREEN (1900 775);
DISPLAY INVISIBLE (1900 775);
FORCEPROP 1 LAST HDL_TAP TRUE
J 0
(2170 645);
DISPLAY 2.276596 (2170 645);
PAINT GREEN (2170 645);
DISPLAY INVISIBLE (2170 645);
FORCEADD TAP..3
(1600 2575);
FORCEPROP 3 LASTPIN (1600 2525) SIG_NAME P3E_CPU0_PE1_PCH_R_RXP<12>
J 0
(1610 2535);
DISPLAY 0.659574 (1610 2535);
PAINT MONO (1610 2535);
DISPLAY INVISIBLE (1610 2535);
FORCEPROP 1 LASTPIN (1600 2525) BN 12
R 1
J 0
(1593 2513);
DISPLAY 0.617021 (1593 2513);
PAINT GREEN (1593 2513);
FORCEPROP 1 LAST PATH I231
J 0
(1598 2575);
DISPLAY 0.872340 (1598 2575);
PAINT GREEN (1598 2575);
DISPLAY INVISIBLE (1598 2575);
FORCEPROP 2 LAST CDS_LIB mstr_standard
J 0
(1600 2575);
PAINT ORANGE (1600 2575);
DISPLAY INVISIBLE (1600 2575);
FORCEPROP 1 LAST BODY_TYPE PLUMBING
J 0
(1650 2525);
DISPLAY 2.276596 (1650 2525);
PAINT GREEN (1650 2525);
DISPLAY INVISIBLE (1650 2525);
FORCEPROP 1 LAST HDL_TAP TRUE
J 0
(1920 2445);
DISPLAY 2.276596 (1920 2445);
PAINT GREEN (1920 2445);
DISPLAY INVISIBLE (1920 2445);
FORCEADD CAP..1
R 2
(1600 2325);
FORCEPROP 0 LAST GROUP PCIE_UPLINK
J 0
(1450 2575);
DISPLAY 0.638298 (1450 2575);
PAINT BROWN (1450 2575);
DISPLAY BOTH (1450 2575);
FORCEPROP 1 LAST LOCATION C3M3
J 2
(1550 2425);
DISPLAY 0.617021 (1550 2425);
PAINT AQUA (1550 2425);
FORCEPROP 1 LAST VALUE 0.22UF
J 2
(1550 2375);
DISPLAY 0.617021 (1550 2375);
PAINT SKYBLUE (1550 2375);
FORCEPROP 1 LASTPIN (1600 2425) $PN 1
J 2
(1590 2405);
DISPLAY 0.617021 (1590 2405);
PAINT ORANGE (1590 2405);
FORCEPROP 1 LASTPIN (1600 2225) $PN 2
J 2
(1590 2205);
DISPLAY 0.617021 (1590 2205);
PAINT ORANGE (1590 2205);
FORCEPROP 1 LAST MATERIAL X7R
J 2
(1550 2225);
DISPLAY 0.617021 (1550 2225);
PAINT SKYBLUE (1550 2225);
FORCEPROP 1 LAST VOLTAGE 16V
J 2
(1550 2325);
DISPLAY 0.617021 (1550 2325);
PAINT SKYBLUE (1550 2325);
FORCEPROP 1 LAST TOLERANCE 10%
J 2
(1550 2275);
DISPLAY 0.617021 (1550 2275);
PAINT SKYBLUE (1550 2275);
FORCEPROP 1 LAST PART_NUMBER A36096-155
J 2
(1550 2175);
DISPLAY 0.617021 (1550 2175);
PAINT BLUE (1550 2175);
FORCEPROP 1 LAST PACK_TYPE 0402
J 2
(1550 2125);
DISPLAY 0.617021 (1550 2125);
PAINT SKYBLUE (1550 2125);
FORCEPROP 2 LAST ROOM OCP_STEERING
J 2
(1600 2325);
PAINT MONO (1600 2325);
DISPLAY INVISIBLE (1600 2325);
FORCEPROP 1 LAST PATH I232
J 2
(1550 2475);
DISPLAY 0.978723 (1550 2475);
PAINT WHITE (1550 2475);
DISPLAY INVISIBLE (1550 2475);
FORCEPROP 2 LAST CDS_LOCATION C3M3
J 2
(1550 2425);
DISPLAY 0.617021 (1550 2425);
PAINT AQUA (1550 2425);
DISPLAY INVISIBLE (1550 2425);
FORCEPROP 2 LAST $SEC 1
J 0
(1550 2525);
DISPLAY 0.680851 (1550 2525);
PAINT MONO (1550 2525);
DISPLAY INVISIBLE (1550 2525);
FORCEPROP 2 LAST CDS_SEC 1
J 0
(1550 2525);
DISPLAY 1.021277 (1550 2525);
PAINT ORANGE (1550 2525);
DISPLAY INVISIBLE (1550 2525);
FORCEPROP 2 LAST CDS_LIB mstr_discrete
J 0
(1600 2325);
PAINT ORANGE (1600 2325);
DISPLAY INVISIBLE (1600 2325);
FORCEADD TAP..3
(1400 2575);
FORCEPROP 3 LASTPIN (1400 2525) SIG_NAME P3E_CPU0_PE1_PCH_R_RXP<13>
J 0
(1410 2535);
DISPLAY 0.659574 (1410 2535);
PAINT MONO (1410 2535);
DISPLAY INVISIBLE (1410 2535);
FORCEPROP 1 LASTPIN (1400 2525) BN 13
R 1
J 0
(1393 2513);
DISPLAY 0.617021 (1393 2513);
PAINT GREEN (1393 2513);
FORCEPROP 1 LAST PATH I233
J 0
(1398 2575);
DISPLAY 0.872340 (1398 2575);
PAINT GREEN (1398 2575);
DISPLAY INVISIBLE (1398 2575);
FORCEPROP 2 LAST CDS_LIB mstr_standard
J 0
(1400 2575);
PAINT ORANGE (1400 2575);
DISPLAY INVISIBLE (1400 2575);
FORCEPROP 1 LAST BODY_TYPE PLUMBING
J 0
(1450 2525);
DISPLAY 2.276596 (1450 2525);
PAINT GREEN (1450 2525);
DISPLAY INVISIBLE (1450 2525);
FORCEPROP 1 LAST HDL_TAP TRUE
J 0
(1720 2445);
DISPLAY 2.276596 (1720 2445);
PAINT GREEN (1720 2445);
DISPLAY INVISIBLE (1720 2445);
FORCEADD CAP..1
R 2
(1200 2325);
FORCEPROP 0 LAST GROUP PCIE_UPLINK
J 0
(1025 2575);
DISPLAY 0.638298 (1025 2575);
PAINT BROWN (1025 2575);
DISPLAY BOTH (1025 2575);
FORCEPROP 1 LAST PACK_TYPE 0402
J 2
(1150 2125);
DISPLAY 0.617021 (1150 2125);
PAINT SKYBLUE (1150 2125);
FORCEPROP 1 LASTPIN (1200 2425) $PN 1
J 2
(1190 2405);
DISPLAY 0.617021 (1190 2405);
PAINT ORANGE (1190 2405);
FORCEPROP 1 LASTPIN (1200 2225) $PN 2
J 2
(1190 2205);
DISPLAY 0.617021 (1190 2205);
PAINT ORANGE (1190 2205);
FORCEPROP 1 LAST MATERIAL X7R
J 2
(1150 2225);
DISPLAY 0.617021 (1150 2225);
PAINT SKYBLUE (1150 2225);
FORCEPROP 1 LAST VOLTAGE 16V
J 2
(1150 2325);
DISPLAY 0.617021 (1150 2325);
PAINT SKYBLUE (1150 2325);
FORCEPROP 1 LAST VALUE 0.22UF
J 2
(1150 2375);
DISPLAY 0.617021 (1150 2375);
PAINT SKYBLUE (1150 2375);
FORCEPROP 1 LAST PART_NUMBER A36096-155
J 2
(1150 2175);
DISPLAY 0.617021 (1150 2175);
PAINT BLUE (1150 2175);
FORCEPROP 1 LAST LOCATION C3M11
J 2
(1150 2425);
DISPLAY 0.617021 (1150 2425);
PAINT AQUA (1150 2425);
FORCEPROP 1 LAST TOLERANCE 10%
J 2
(1150 2275);
DISPLAY 0.617021 (1150 2275);
PAINT SKYBLUE (1150 2275);
FORCEPROP 2 LAST ROOM OCP_STEERING
J 2
(1200 2325);
PAINT MONO (1200 2325);
DISPLAY INVISIBLE (1200 2325);
FORCEPROP 1 LAST PATH I234
J 2
(1150 2475);
DISPLAY 0.978723 (1150 2475);
PAINT WHITE (1150 2475);
DISPLAY INVISIBLE (1150 2475);
FORCEPROP 2 LAST CDS_LOCATION C3M11
J 2
(1150 2425);
DISPLAY 0.617021 (1150 2425);
PAINT AQUA (1150 2425);
DISPLAY INVISIBLE (1150 2425);
FORCEPROP 2 LAST $SEC 1
J 0
(1150 2525);
DISPLAY 0.680851 (1150 2525);
PAINT MONO (1150 2525);
DISPLAY INVISIBLE (1150 2525);
FORCEPROP 2 LAST CDS_SEC 1
J 0
(1150 2525);
DISPLAY 1.021277 (1150 2525);
PAINT ORANGE (1150 2525);
DISPLAY INVISIBLE (1150 2525);
FORCEPROP 2 LAST CDS_LIB mstr_discrete
J 0
(1200 2325);
PAINT ORANGE (1200 2325);
DISPLAY INVISIBLE (1200 2325);
FORCEADD TAP..3
(1200 2575);
FORCEPROP 3 LASTPIN (1200 2525) SIG_NAME P3E_CPU0_PE1_PCH_R_RXP<14>
J 0
(1210 2535);
DISPLAY 0.659574 (1210 2535);
PAINT MONO (1210 2535);
DISPLAY INVISIBLE (1210 2535);
FORCEPROP 1 LASTPIN (1200 2525) BN 14
R 1
J 0
(1193 2513);
DISPLAY 0.617021 (1193 2513);
PAINT GREEN (1193 2513);
FORCEPROP 1 LAST PATH I235
J 0
(1198 2575);
DISPLAY 0.872340 (1198 2575);
PAINT GREEN (1198 2575);
DISPLAY INVISIBLE (1198 2575);
FORCEPROP 2 LAST CDS_LIB mstr_standard
J 0
(1200 2575);
PAINT ORANGE (1200 2575);
DISPLAY INVISIBLE (1200 2575);
FORCEPROP 1 LAST BODY_TYPE PLUMBING
J 0
(1250 2525);
DISPLAY 2.276596 (1250 2525);
PAINT GREEN (1250 2525);
DISPLAY INVISIBLE (1250 2525);
FORCEPROP 1 LAST HDL_TAP TRUE
J 0
(1520 2445);
DISPLAY 2.276596 (1520 2445);
PAINT GREEN (1520 2445);
DISPLAY INVISIBLE (1520 2445);
FORCEADD TAP..3
(1000 2575);
FORCEPROP 3 LASTPIN (1000 2525) SIG_NAME P3E_CPU0_PE1_PCH_R_RXP<15>
J 0
(1010 2535);
DISPLAY 0.659574 (1010 2535);
PAINT MONO (1010 2535);
DISPLAY INVISIBLE (1010 2535);
FORCEPROP 1 LASTPIN (1000 2525) BN 15
R 1
J 0
(993 2513);
DISPLAY 0.617021 (993 2513);
PAINT GREEN (993 2513);
FORCEPROP 1 LAST PATH I236
J 0
(998 2575);
DISPLAY 0.872340 (998 2575);
PAINT GREEN (998 2575);
DISPLAY INVISIBLE (998 2575);
FORCEPROP 2 LAST CDS_LIB mstr_standard
J 0
(1000 2575);
PAINT ORANGE (1000 2575);
DISPLAY INVISIBLE (1000 2575);
FORCEPROP 1 LAST BODY_TYPE PLUMBING
J 0
(1050 2525);
DISPLAY 2.276596 (1050 2525);
PAINT GREEN (1050 2525);
DISPLAY INVISIBLE (1050 2525);
FORCEPROP 1 LAST HDL_TAP TRUE
J 0
(1320 2445);
DISPLAY 2.276596 (1320 2445);
PAINT GREEN (1320 2445);
DISPLAY INVISIBLE (1320 2445);
FORCEADD OFFPAGE..1
(825 2625);
FORCEPROP 2 LAST $XR0 117 
J 0
(573 2625);
DISPLAY 0.638298 (573 2625);
PAINT MONO (573 2625);
FORCEPROP 2 LAST PATH I237
J 0
(875 2700);
DISPLAY 1.021277 (875 2700);
PAINT ORANGE (875 2700);
DISPLAY INVISIBLE (875 2700);
FORCEPROP 2 LAST CDS_LIB mstr_standard
J 0
(825 2625);
PAINT ORANGE (825 2625);
DISPLAY INVISIBLE (825 2625);
FORCEPROP 1 LAST OFFPAGE TRUE
J 0
(1145 2495);
PAINT GREEN (1145 2495);
DISPLAY INVISIBLE (1145 2495);
FORCEPROP 1 LAST COMMENT_BODY TRUE
J 0
(945 2525);
DISPLAY 2.276596 (945 2525);
PAINT GREEN (945 2525);
DISPLAY INVISIBLE (945 2525);
FORCEADD TAP..7
(1600 1775);
FORCEPROP 3 LASTPIN (1600 1825) SIG_NAME P3E_CPU0_PE1_PCH_RXP<12>
J 0
(1610 1835);
DISPLAY 0.659574 (1610 1835);
PAINT MONO (1610 1835);
DISPLAY INVISIBLE (1610 1835);
FORCEPROP 1 LASTPIN (1600 1825) BN 12
R 1
J 0
(1593 1773);
DISPLAY 0.617021 (1593 1773);
PAINT GREEN (1593 1773);
FORCEPROP 1 LAST PATH I238
J 0
(1598 1775);
DISPLAY 0.872340 (1598 1775);
PAINT GREEN (1598 1775);
DISPLAY INVISIBLE (1598 1775);
FORCEPROP 2 LAST CDS_LIB mstr_standard
J 0
(1600 1775);
PAINT ORANGE (1600 1775);
DISPLAY INVISIBLE (1600 1775);
FORCEPROP 1 LAST BODY_TYPE PLUMBING
J 0
(1650 1775);
DISPLAY 2.276596 (1650 1775);
PAINT GREEN (1650 1775);
DISPLAY INVISIBLE (1650 1775);
FORCEPROP 1 LAST HDL_TAP TRUE
J 0
(1920 1645);
DISPLAY 2.276596 (1920 1645);
PAINT GREEN (1920 1645);
DISPLAY INVISIBLE (1920 1645);
FORCEADD CAP..1
R 2
(1400 2025);
FORCEPROP 0 LAST GROUP PCIE_UPLINK
J 0
(1250 1750);
DISPLAY 0.638298 (1250 1750);
PAINT BROWN (1250 1750);
DISPLAY BOTH (1250 1750);
FORCEPROP 1 LAST VOLTAGE 16V
J 2
(1350 2025);
DISPLAY 0.617021 (1350 2025);
PAINT SKYBLUE (1350 2025);
FORCEPROP 1 LASTPIN (1400 2125) $PN 1
J 2
(1390 2105);
DISPLAY 0.617021 (1390 2105);
PAINT ORANGE (1390 2105);
FORCEPROP 1 LASTPIN (1400 1925) $PN 2
J 2
(1390 1905);
DISPLAY 0.617021 (1390 1905);
PAINT ORANGE (1390 1905);
FORCEPROP 1 LAST MATERIAL X7R
J 2
(1350 1925);
DISPLAY 0.617021 (1350 1925);
PAINT SKYBLUE (1350 1925);
FORCEPROP 1 LAST PACK_TYPE 0402
J 2
(1350 1825);
DISPLAY 0.617021 (1350 1825);
PAINT SKYBLUE (1350 1825);
FORCEPROP 1 LAST PART_NUMBER A36096-155
J 2
(1350 1875);
DISPLAY 0.617021 (1350 1875);
PAINT BLUE (1350 1875);
FORCEPROP 1 LAST LOCATION C3M13
J 2
(1350 2125);
DISPLAY 0.617021 (1350 2125);
PAINT AQUA (1350 2125);
FORCEPROP 1 LAST VALUE 0.22UF
J 2
(1350 2075);
DISPLAY 0.617021 (1350 2075);
PAINT SKYBLUE (1350 2075);
FORCEPROP 1 LAST TOLERANCE 10%
J 2
(1350 1975);
DISPLAY 0.617021 (1350 1975);
PAINT SKYBLUE (1350 1975);
FORCEPROP 2 LAST ROOM OCP_STEERING
J 2
(1400 2025);
PAINT MONO (1400 2025);
DISPLAY INVISIBLE (1400 2025);
FORCEPROP 1 LAST PATH I239
J 2
(1350 2175);
DISPLAY 0.978723 (1350 2175);
PAINT WHITE (1350 2175);
DISPLAY INVISIBLE (1350 2175);
FORCEPROP 2 LAST CDS_LOCATION C3M13
J 2
(1350 2125);
DISPLAY 0.617021 (1350 2125);
PAINT AQUA (1350 2125);
DISPLAY INVISIBLE (1350 2125);
FORCEPROP 2 LAST $SEC 1
J 0
(1350 2225);
DISPLAY 0.680851 (1350 2225);
PAINT MONO (1350 2225);
DISPLAY INVISIBLE (1350 2225);
FORCEPROP 2 LAST CDS_SEC 1
J 0
(1350 2225);
DISPLAY 1.021277 (1350 2225);
PAINT ORANGE (1350 2225);
DISPLAY INVISIBLE (1350 2225);
FORCEPROP 2 LAST CDS_LIB mstr_discrete
J 0
(1400 2025);
PAINT ORANGE (1400 2025);
DISPLAY INVISIBLE (1400 2025);
FORCEADD TAP..7
(-150 4100);
FORCEPROP 3 LASTPIN (-150 4150) SIG_NAME P3E_CPU0_PE2_SS_C_TXP<12>
J 0
(-140 4160);
DISPLAY 0.659574 (-140 4160);
PAINT MONO (-140 4160);
DISPLAY INVISIBLE (-140 4160);
FORCEPROP 1 LASTPIN (-150 4150) BN 12
R 1
J 0
(-157 4098);
DISPLAY 0.617021 (-157 4098);
PAINT GREEN (-157 4098);
FORCEPROP 1 LAST PATH I24
J 0
(-152 4100);
DISPLAY 0.872340 (-152 4100);
PAINT GREEN (-152 4100);
DISPLAY INVISIBLE (-152 4100);
FORCEPROP 2 LAST CDS_LIB mstr_standard
J 0
(-150 4100);
PAINT ORANGE (-150 4100);
DISPLAY INVISIBLE (-150 4100);
FORCEPROP 1 LAST BODY_TYPE PLUMBING
J 0
(-100 4100);
DISPLAY 2.276596 (-100 4100);
PAINT GREEN (-100 4100);
DISPLAY INVISIBLE (-100 4100);
FORCEPROP 1 LAST HDL_TAP TRUE
J 0
(170 3970);
DISPLAY 2.276596 (170 3970);
PAINT GREEN (170 3970);
DISPLAY INVISIBLE (170 3970);
FORCEADD TAP..7
(1400 1775);
FORCEPROP 3 LASTPIN (1400 1825) SIG_NAME P3E_CPU0_PE1_PCH_RXP<13>
J 0
(1410 1835);
DISPLAY 0.659574 (1410 1835);
PAINT MONO (1410 1835);
DISPLAY INVISIBLE (1410 1835);
FORCEPROP 1 LASTPIN (1400 1825) BN 13
R 1
J 0
(1393 1773);
DISPLAY 0.617021 (1393 1773);
PAINT GREEN (1393 1773);
FORCEPROP 1 LAST PATH I240
J 0
(1398 1775);
DISPLAY 0.872340 (1398 1775);
PAINT GREEN (1398 1775);
DISPLAY INVISIBLE (1398 1775);
FORCEPROP 2 LAST CDS_LIB mstr_standard
J 0
(1400 1775);
PAINT ORANGE (1400 1775);
DISPLAY INVISIBLE (1400 1775);
FORCEPROP 1 LAST BODY_TYPE PLUMBING
J 0
(1450 1775);
DISPLAY 2.276596 (1450 1775);
PAINT GREEN (1450 1775);
DISPLAY INVISIBLE (1450 1775);
FORCEPROP 1 LAST HDL_TAP TRUE
J 0
(1720 1645);
DISPLAY 2.276596 (1720 1645);
PAINT GREEN (1720 1645);
DISPLAY INVISIBLE (1720 1645);
FORCEADD TAP..7
(1200 1775);
FORCEPROP 3 LASTPIN (1200 1825) SIG_NAME P3E_CPU0_PE1_PCH_RXP<14>
J 0
(1210 1835);
DISPLAY 0.659574 (1210 1835);
PAINT MONO (1210 1835);
DISPLAY INVISIBLE (1210 1835);
FORCEPROP 1 LASTPIN (1200 1825) BN 14
R 1
J 0
(1193 1773);
DISPLAY 0.617021 (1193 1773);
PAINT GREEN (1193 1773);
FORCEPROP 1 LAST PATH I241
J 0
(1198 1775);
DISPLAY 0.872340 (1198 1775);
PAINT GREEN (1198 1775);
DISPLAY INVISIBLE (1198 1775);
FORCEPROP 2 LAST CDS_LIB mstr_standard
J 0
(1200 1775);
PAINT ORANGE (1200 1775);
DISPLAY INVISIBLE (1200 1775);
FORCEPROP 1 LAST BODY_TYPE PLUMBING
J 0
(1250 1775);
DISPLAY 2.276596 (1250 1775);
PAINT GREEN (1250 1775);
DISPLAY INVISIBLE (1250 1775);
FORCEPROP 1 LAST HDL_TAP TRUE
J 0
(1520 1645);
DISPLAY 2.276596 (1520 1645);
PAINT GREEN (1520 1645);
DISPLAY INVISIBLE (1520 1645);
FORCEADD TAP..3
(1650 1575);
FORCEPROP 3 LASTPIN (1650 1525) SIG_NAME P3E_CPU0_PE1_PCH_R_RXN<12>
J 0
(1660 1535);
DISPLAY 0.659574 (1660 1535);
PAINT MONO (1660 1535);
DISPLAY INVISIBLE (1660 1535);
FORCEPROP 1 LASTPIN (1650 1525) BN 12
R 1
J 0
(1643 1513);
DISPLAY 0.617021 (1643 1513);
PAINT GREEN (1643 1513);
FORCEPROP 1 LAST PATH I242
J 0
(1648 1575);
DISPLAY 0.872340 (1648 1575);
PAINT GREEN (1648 1575);
DISPLAY INVISIBLE (1648 1575);
FORCEPROP 2 LAST CDS_LIB mstr_standard
J 0
(1650 1575);
PAINT ORANGE (1650 1575);
DISPLAY INVISIBLE (1650 1575);
FORCEPROP 1 LAST BODY_TYPE PLUMBING
J 0
(1700 1525);
DISPLAY 2.276596 (1700 1525);
PAINT GREEN (1700 1525);
DISPLAY INVISIBLE (1700 1525);
FORCEPROP 1 LAST HDL_TAP TRUE
J 0
(1970 1445);
DISPLAY 2.276596 (1970 1445);
PAINT GREEN (1970 1445);
DISPLAY INVISIBLE (1970 1445);
FORCEADD TAP..3
(1450 1575);
FORCEPROP 3 LASTPIN (1450 1525) SIG_NAME P3E_CPU0_PE1_PCH_R_RXN<13>
J 0
(1460 1535);
DISPLAY 0.659574 (1460 1535);
PAINT MONO (1460 1535);
DISPLAY INVISIBLE (1460 1535);
FORCEPROP 1 LASTPIN (1450 1525) BN 13
R 1
J 0
(1443 1513);
DISPLAY 0.617021 (1443 1513);
PAINT GREEN (1443 1513);
FORCEPROP 1 LAST PATH I243
J 0
(1448 1575);
DISPLAY 0.872340 (1448 1575);
PAINT GREEN (1448 1575);
DISPLAY INVISIBLE (1448 1575);
FORCEPROP 2 LAST CDS_LIB mstr_standard
J 0
(1450 1575);
PAINT ORANGE (1450 1575);
DISPLAY INVISIBLE (1450 1575);
FORCEPROP 1 LAST BODY_TYPE PLUMBING
J 0
(1500 1525);
DISPLAY 2.276596 (1500 1525);
PAINT GREEN (1500 1525);
DISPLAY INVISIBLE (1500 1525);
FORCEPROP 1 LAST HDL_TAP TRUE
J 0
(1770 1445);
DISPLAY 2.276596 (1770 1445);
PAINT GREEN (1770 1445);
DISPLAY INVISIBLE (1770 1445);
FORCEADD CAP..1
R 2
(1650 1325);
FORCEPROP 1 LAST PACK_TYPE 0402
J 2
(1600 1125);
DISPLAY 0.617021 (1600 1125);
PAINT SKYBLUE (1600 1125);
FORCEPROP 1 LAST PART_NUMBER A36096-155
J 2
(1600 1175);
DISPLAY 0.617021 (1600 1175);
PAINT BLUE (1600 1175);
FORCEPROP 1 LASTPIN (1650 1425) $PN 1
J 2
(1640 1405);
DISPLAY 0.617021 (1640 1405);
PAINT ORANGE (1640 1405);
FORCEPROP 1 LASTPIN (1650 1225) $PN 2
J 2
(1640 1205);
DISPLAY 0.617021 (1640 1205);
PAINT ORANGE (1640 1205);
FORCEPROP 1 LAST MATERIAL X7R
J 2
(1600 1225);
DISPLAY 0.617021 (1600 1225);
PAINT SKYBLUE (1600 1225);
FORCEPROP 1 LAST VOLTAGE 16V
J 2
(1600 1325);
DISPLAY 0.617021 (1600 1325);
PAINT SKYBLUE (1600 1325);
FORCEPROP 1 LAST TOLERANCE 10%
J 2
(1600 1275);
DISPLAY 0.617021 (1600 1275);
PAINT SKYBLUE (1600 1275);
FORCEPROP 1 LAST VALUE 0.22UF
J 2
(1600 1375);
DISPLAY 0.617021 (1600 1375);
PAINT SKYBLUE (1600 1375);
FORCEPROP 1 LAST LOCATION C3M4
J 2
(1600 1425);
DISPLAY 0.617021 (1600 1425);
PAINT AQUA (1600 1425);
FORCEPROP 0 LAST GROUP PCIE_UPLINK
J 0
(1500 1475);
DISPLAY 0.638298 (1500 1475);
PAINT BROWN (1500 1475);
DISPLAY BOTH (1500 1475);
FORCEPROP 2 LAST ROOM OCP_STEERING
J 2
(1650 1325);
PAINT MONO (1650 1325);
DISPLAY INVISIBLE (1650 1325);
FORCEPROP 1 LAST PATH I244
J 2
(1600 1475);
DISPLAY 0.978723 (1600 1475);
PAINT WHITE (1600 1475);
DISPLAY INVISIBLE (1600 1475);
FORCEPROP 2 LAST CDS_LOCATION C3M4
J 2
(1600 1425);
DISPLAY 0.617021 (1600 1425);
PAINT AQUA (1600 1425);
DISPLAY INVISIBLE (1600 1425);
FORCEPROP 2 LAST $SEC 1
J 0
(1600 1525);
DISPLAY 0.680851 (1600 1525);
PAINT MONO (1600 1525);
DISPLAY INVISIBLE (1600 1525);
FORCEPROP 2 LAST CDS_SEC 1
J 0
(1600 1525);
DISPLAY 1.021277 (1600 1525);
PAINT ORANGE (1600 1525);
DISPLAY INVISIBLE (1600 1525);
FORCEPROP 2 LAST CDS_LIB mstr_discrete
J 0
(1650 1325);
PAINT ORANGE (1650 1325);
DISPLAY INVISIBLE (1650 1325);
FORCEADD TAP..3
(1250 1575);
FORCEPROP 3 LASTPIN (1250 1525) SIG_NAME P3E_CPU0_PE1_PCH_R_RXN<14>
J 0
(1260 1535);
DISPLAY 0.659574 (1260 1535);
PAINT MONO (1260 1535);
DISPLAY INVISIBLE (1260 1535);
FORCEPROP 1 LASTPIN (1250 1525) BN 14
R 1
J 0
(1243 1513);
DISPLAY 0.617021 (1243 1513);
PAINT GREEN (1243 1513);
FORCEPROP 1 LAST PATH I245
J 0
(1248 1575);
DISPLAY 0.872340 (1248 1575);
PAINT GREEN (1248 1575);
DISPLAY INVISIBLE (1248 1575);
FORCEPROP 2 LAST CDS_LIB mstr_standard
J 0
(1250 1575);
PAINT ORANGE (1250 1575);
DISPLAY INVISIBLE (1250 1575);
FORCEPROP 1 LAST BODY_TYPE PLUMBING
J 0
(1300 1525);
DISPLAY 2.276596 (1300 1525);
PAINT GREEN (1300 1525);
DISPLAY INVISIBLE (1300 1525);
FORCEPROP 1 LAST HDL_TAP TRUE
J 0
(1570 1445);
DISPLAY 2.276596 (1570 1445);
PAINT GREEN (1570 1445);
DISPLAY INVISIBLE (1570 1445);
FORCEADD CAP..1
R 2
(1250 1325);
FORCEPROP 1 LAST TOLERANCE 10%
J 2
(1200 1275);
DISPLAY 0.617021 (1200 1275);
PAINT SKYBLUE (1200 1275);
FORCEPROP 1 LAST MATERIAL X7R
J 2
(1200 1225);
DISPLAY 0.617021 (1200 1225);
PAINT SKYBLUE (1200 1225);
FORCEPROP 1 LASTPIN (1250 1225) $PN 2
J 2
(1240 1205);
DISPLAY 0.617021 (1240 1205);
PAINT ORANGE (1240 1205);
FORCEPROP 1 LASTPIN (1250 1425) $PN 1
J 2
(1240 1405);
DISPLAY 0.617021 (1240 1405);
PAINT ORANGE (1240 1405);
FORCEPROP 1 LAST VOLTAGE 16V
J 2
(1200 1325);
DISPLAY 0.617021 (1200 1325);
PAINT SKYBLUE (1200 1325);
FORCEPROP 1 LAST PACK_TYPE 0402
J 2
(1200 1125);
DISPLAY 0.617021 (1200 1125);
PAINT SKYBLUE (1200 1125);
FORCEPROP 1 LAST VALUE 0.22UF
J 2
(1200 1375);
DISPLAY 0.617021 (1200 1375);
PAINT SKYBLUE (1200 1375);
FORCEPROP 1 LAST PART_NUMBER A36096-155
J 2
(1200 1175);
DISPLAY 0.617021 (1200 1175);
PAINT BLUE (1200 1175);
FORCEPROP 1 LAST LOCATION C3M12
J 2
(1200 1425);
DISPLAY 0.617021 (1200 1425);
PAINT AQUA (1200 1425);
FORCEPROP 0 LAST GROUP PCIE_UPLINK
J 0
(1100 1475);
DISPLAY 0.638298 (1100 1475);
PAINT BROWN (1100 1475);
DISPLAY BOTH (1100 1475);
FORCEPROP 2 LAST ROOM OCP_STEERING
J 2
(1250 1325);
PAINT MONO (1250 1325);
DISPLAY INVISIBLE (1250 1325);
FORCEPROP 1 LAST PATH I246
J 2
(1200 1475);
DISPLAY 0.978723 (1200 1475);
PAINT WHITE (1200 1475);
DISPLAY INVISIBLE (1200 1475);
FORCEPROP 2 LAST CDS_LOCATION C3M12
J 2
(1200 1425);
DISPLAY 0.617021 (1200 1425);
PAINT AQUA (1200 1425);
DISPLAY INVISIBLE (1200 1425);
FORCEPROP 2 LAST $SEC 1
J 0
(1200 1525);
DISPLAY 0.680851 (1200 1525);
PAINT MONO (1200 1525);
DISPLAY INVISIBLE (1200 1525);
FORCEPROP 2 LAST CDS_SEC 1
J 0
(1200 1525);
DISPLAY 1.021277 (1200 1525);
PAINT ORANGE (1200 1525);
DISPLAY INVISIBLE (1200 1525);
FORCEPROP 2 LAST CDS_LIB mstr_discrete
J 0
(1250 1325);
PAINT ORANGE (1250 1325);
DISPLAY INVISIBLE (1250 1325);
FORCEADD CAP..1
R 2
(1000 2025);
FORCEPROP 0 LAST GROUP PCIE_UPLINK
J 0
(750 1750);
DISPLAY 0.638298 (750 1750);
PAINT BROWN (750 1750);
DISPLAY BOTH (750 1750);
FORCEPROP 1 LAST VALUE 0.22UF
J 2
(950 2075);
DISPLAY 0.617021 (950 2075);
PAINT SKYBLUE (950 2075);
FORCEPROP 1 LAST LOCATION C3M2
J 2
(950 2125);
DISPLAY 0.617021 (950 2125);
PAINT AQUA (950 2125);
FORCEPROP 1 LASTPIN (1000 2125) $PN 1
J 2
(990 2105);
DISPLAY 0.617021 (990 2105);
PAINT ORANGE (990 2105);
FORCEPROP 1 LASTPIN (1000 1925) $PN 2
J 2
(990 1905);
DISPLAY 0.617021 (990 1905);
PAINT ORANGE (990 1905);
FORCEPROP 1 LAST MATERIAL X7R
J 2
(950 1925);
DISPLAY 0.617021 (950 1925);
PAINT SKYBLUE (950 1925);
FORCEPROP 1 LAST VOLTAGE 16V
J 2
(950 2025);
DISPLAY 0.617021 (950 2025);
PAINT SKYBLUE (950 2025);
FORCEPROP 1 LAST PACK_TYPE 0402
J 2
(950 1825);
DISPLAY 0.617021 (950 1825);
PAINT SKYBLUE (950 1825);
FORCEPROP 1 LAST TOLERANCE 10%
J 2
(950 1975);
DISPLAY 0.617021 (950 1975);
PAINT SKYBLUE (950 1975);
FORCEPROP 1 LAST PART_NUMBER A36096-155
J 2
(950 1875);
DISPLAY 0.617021 (950 1875);
PAINT BLUE (950 1875);
FORCEPROP 2 LAST ROOM OCP_STEERING
J 2
(1000 2025);
PAINT MONO (1000 2025);
DISPLAY INVISIBLE (1000 2025);
FORCEPROP 1 LAST PATH I247
J 2
(950 2175);
DISPLAY 0.978723 (950 2175);
PAINT WHITE (950 2175);
DISPLAY INVISIBLE (950 2175);
FORCEPROP 2 LAST CDS_LOCATION C3M2
J 2
(950 2125);
DISPLAY 0.617021 (950 2125);
PAINT AQUA (950 2125);
DISPLAY INVISIBLE (950 2125);
FORCEPROP 2 LAST $SEC 1
J 0
(950 2225);
DISPLAY 0.680851 (950 2225);
PAINT MONO (950 2225);
DISPLAY INVISIBLE (950 2225);
FORCEPROP 2 LAST CDS_SEC 1
J 0
(950 2225);
DISPLAY 1.021277 (950 2225);
PAINT ORANGE (950 2225);
DISPLAY INVISIBLE (950 2225);
FORCEPROP 2 LAST CDS_LIB mstr_discrete
J 0
(1000 2025);
PAINT ORANGE (1000 2025);
DISPLAY INVISIBLE (1000 2025);
FORCEADD TAP..7
(1000 1775);
FORCEPROP 3 LASTPIN (1000 1825) SIG_NAME P3E_CPU0_PE1_PCH_RXP<15>
J 0
(1010 1835);
DISPLAY 0.659574 (1010 1835);
PAINT MONO (1010 1835);
DISPLAY INVISIBLE (1010 1835);
FORCEPROP 1 LASTPIN (1000 1825) BN 15
R 1
J 0
(993 1773);
DISPLAY 0.617021 (993 1773);
PAINT GREEN (993 1773);
FORCEPROP 1 LAST PATH I248
J 0
(998 1775);
DISPLAY 0.872340 (998 1775);
PAINT GREEN (998 1775);
DISPLAY INVISIBLE (998 1775);
FORCEPROP 2 LAST CDS_LIB mstr_standard
J 0
(1000 1775);
PAINT ORANGE (1000 1775);
DISPLAY INVISIBLE (1000 1775);
FORCEPROP 1 LAST BODY_TYPE PLUMBING
J 0
(1050 1775);
DISPLAY 2.276596 (1050 1775);
PAINT GREEN (1050 1775);
DISPLAY INVISIBLE (1050 1775);
FORCEPROP 1 LAST HDL_TAP TRUE
J 0
(1320 1645);
DISPLAY 2.276596 (1320 1645);
PAINT GREEN (1320 1645);
DISPLAY INVISIBLE (1320 1645);
FORCEADD OFFPAGE..1
(875 1625);
FORCEPROP 2 LAST $XR0 117 
J 0
(593 1625);
DISPLAY 0.638298 (593 1625);
PAINT MONO (593 1625);
FORCEPROP 2 LAST PATH I249
J 0
(925 1700);
DISPLAY 1.021277 (925 1700);
PAINT ORANGE (925 1700);
DISPLAY INVISIBLE (925 1700);
FORCEPROP 2 LAST CDS_LIB mstr_standard
J 0
(875 1625);
PAINT ORANGE (875 1625);
DISPLAY INVISIBLE (875 1625);
FORCEPROP 1 LAST OFFPAGE TRUE
J 0
(1195 1495);
PAINT GREEN (1195 1495);
DISPLAY INVISIBLE (1195 1495);
FORCEPROP 1 LAST COMMENT_BODY TRUE
J 0
(995 1525);
DISPLAY 2.276596 (995 1525);
PAINT GREEN (995 1525);
DISPLAY INVISIBLE (995 1525);
FORCEADD TAP..3
(100 3900);
FORCEPROP 3 LASTPIN (100 3850) SIG_NAME P3E_CPU0_PE2_SS_TXN<11>
J 0
(110 3860);
DISPLAY 0.659574 (110 3860);
PAINT MONO (110 3860);
DISPLAY INVISIBLE (110 3860);
FORCEPROP 1 LASTPIN (100 3850) BN 11
R 1
J 0
(93 3838);
DISPLAY 0.617021 (93 3838);
PAINT GREEN (93 3838);
FORCEPROP 1 LAST PATH I25
J 0
(98 3900);
DISPLAY 0.872340 (98 3900);
PAINT GREEN (98 3900);
DISPLAY INVISIBLE (98 3900);
FORCEPROP 2 LAST CDS_LIB mstr_standard
J 0
(100 3900);
PAINT ORANGE (100 3900);
DISPLAY INVISIBLE (100 3900);
FORCEPROP 1 LAST BODY_TYPE PLUMBING
J 0
(150 3850);
DISPLAY 2.276596 (150 3850);
PAINT GREEN (150 3850);
DISPLAY INVISIBLE (150 3850);
FORCEPROP 1 LAST HDL_TAP TRUE
J 0
(420 3770);
DISPLAY 2.276596 (420 3770);
PAINT GREEN (420 3770);
DISPLAY INVISIBLE (420 3770);
FORCEADD TAP..3
(1050 1575);
FORCEPROP 3 LASTPIN (1050 1525) SIG_NAME P3E_CPU0_PE1_PCH_R_RXN<15>
J 0
(1060 1535);
DISPLAY 0.659574 (1060 1535);
PAINT MONO (1060 1535);
DISPLAY INVISIBLE (1060 1535);
FORCEPROP 1 LASTPIN (1050 1525) BN 15
R 1
J 0
(1043 1513);
DISPLAY 0.617021 (1043 1513);
PAINT GREEN (1043 1513);
FORCEPROP 1 LAST PATH I250
J 0
(1048 1575);
DISPLAY 0.872340 (1048 1575);
PAINT GREEN (1048 1575);
DISPLAY INVISIBLE (1048 1575);
FORCEPROP 2 LAST CDS_LIB mstr_standard
J 0
(1050 1575);
PAINT ORANGE (1050 1575);
DISPLAY INVISIBLE (1050 1575);
FORCEPROP 1 LAST BODY_TYPE PLUMBING
J 0
(1100 1525);
DISPLAY 2.276596 (1100 1525);
PAINT GREEN (1100 1525);
DISPLAY INVISIBLE (1100 1525);
FORCEPROP 1 LAST HDL_TAP TRUE
J 0
(1370 1445);
DISPLAY 2.276596 (1370 1445);
PAINT GREEN (1370 1445);
DISPLAY INVISIBLE (1370 1445);
FORCEADD TAP..7
(1450 775);
FORCEPROP 3 LASTPIN (1450 825) SIG_NAME P3E_CPU0_PE1_PCH_RXN<13>
J 0
(1460 835);
DISPLAY 0.659574 (1460 835);
PAINT MONO (1460 835);
DISPLAY INVISIBLE (1460 835);
FORCEPROP 1 LASTPIN (1450 825) BN 13
R 1
J 0
(1443 773);
DISPLAY 0.617021 (1443 773);
PAINT GREEN (1443 773);
FORCEPROP 1 LAST PATH I251
J 0
(1448 775);
DISPLAY 0.872340 (1448 775);
PAINT GREEN (1448 775);
DISPLAY INVISIBLE (1448 775);
FORCEPROP 2 LAST CDS_LIB mstr_standard
J 0
(1450 775);
PAINT ORANGE (1450 775);
DISPLAY INVISIBLE (1450 775);
FORCEPROP 1 LAST BODY_TYPE PLUMBING
J 0
(1500 775);
DISPLAY 2.276596 (1500 775);
PAINT GREEN (1500 775);
DISPLAY INVISIBLE (1500 775);
FORCEPROP 1 LAST HDL_TAP TRUE
J 0
(1770 645);
DISPLAY 2.276596 (1770 645);
PAINT GREEN (1770 645);
DISPLAY INVISIBLE (1770 645);
FORCEADD TAP..7
(1650 775);
FORCEPROP 3 LASTPIN (1650 825) SIG_NAME P3E_CPU0_PE1_PCH_RXN<12>
J 0
(1660 835);
DISPLAY 0.659574 (1660 835);
PAINT MONO (1660 835);
DISPLAY INVISIBLE (1660 835);
FORCEPROP 1 LASTPIN (1650 825) BN 12
R 1
J 0
(1643 773);
DISPLAY 0.617021 (1643 773);
PAINT GREEN (1643 773);
FORCEPROP 1 LAST PATH I252
J 0
(1648 775);
DISPLAY 0.872340 (1648 775);
PAINT GREEN (1648 775);
DISPLAY INVISIBLE (1648 775);
FORCEPROP 2 LAST CDS_LIB mstr_standard
J 0
(1650 775);
PAINT ORANGE (1650 775);
DISPLAY INVISIBLE (1650 775);
FORCEPROP 1 LAST BODY_TYPE PLUMBING
J 0
(1700 775);
DISPLAY 2.276596 (1700 775);
PAINT GREEN (1700 775);
DISPLAY INVISIBLE (1700 775);
FORCEPROP 1 LAST HDL_TAP TRUE
J 0
(1970 645);
DISPLAY 2.276596 (1970 645);
PAINT GREEN (1970 645);
DISPLAY INVISIBLE (1970 645);
FORCEADD CAP..1
R 2
(1450 1025);
FORCEPROP 1 LAST PART_NUMBER A36096-155
J 2
(1400 875);
DISPLAY 0.617021 (1400 875);
PAINT BLUE (1400 875);
FORCEPROP 1 LAST PACK_TYPE 0402
J 2
(1400 825);
DISPLAY 0.617021 (1400 825);
PAINT SKYBLUE (1400 825);
FORCEPROP 1 LASTPIN (1450 1125) $PN 1
J 2
(1440 1105);
DISPLAY 0.617021 (1440 1105);
PAINT ORANGE (1440 1105);
FORCEPROP 1 LASTPIN (1450 925) $PN 2
J 2
(1440 905);
DISPLAY 0.617021 (1440 905);
PAINT ORANGE (1440 905);
FORCEPROP 1 LAST MATERIAL X7R
J 2
(1400 925);
DISPLAY 0.617021 (1400 925);
PAINT SKYBLUE (1400 925);
FORCEPROP 1 LAST VOLTAGE 16V
J 2
(1400 1025);
DISPLAY 0.617021 (1400 1025);
PAINT SKYBLUE (1400 1025);
FORCEPROP 1 LAST TOLERANCE 10%
J 2
(1400 975);
DISPLAY 0.617021 (1400 975);
PAINT SKYBLUE (1400 975);
FORCEPROP 1 LAST VALUE 0.22UF
J 2
(1400 1075);
DISPLAY 0.617021 (1400 1075);
PAINT SKYBLUE (1400 1075);
FORCEPROP 1 LAST LOCATION C3M14
J 2
(1400 1125);
DISPLAY 0.617021 (1400 1125);
PAINT AQUA (1400 1125);
FORCEPROP 0 LAST GROUP PCIE_UPLINK
J 0
(1300 750);
DISPLAY 0.638298 (1300 750);
PAINT BROWN (1300 750);
DISPLAY BOTH (1300 750);
FORCEPROP 2 LAST ROOM OCP_STEERING
J 2
(1450 1025);
PAINT MONO (1450 1025);
DISPLAY INVISIBLE (1450 1025);
FORCEPROP 1 LAST PATH I253
J 2
(1400 1175);
DISPLAY 0.978723 (1400 1175);
PAINT WHITE (1400 1175);
DISPLAY INVISIBLE (1400 1175);
FORCEPROP 2 LAST CDS_LOCATION C3M14
J 2
(1400 1125);
DISPLAY 0.617021 (1400 1125);
PAINT AQUA (1400 1125);
DISPLAY INVISIBLE (1400 1125);
FORCEPROP 2 LAST $SEC 1
J 0
(1400 1225);
DISPLAY 0.680851 (1400 1225);
PAINT MONO (1400 1225);
DISPLAY INVISIBLE (1400 1225);
FORCEPROP 2 LAST CDS_SEC 1
J 0
(1400 1225);
DISPLAY 1.021277 (1400 1225);
PAINT ORANGE (1400 1225);
DISPLAY INVISIBLE (1400 1225);
FORCEPROP 2 LAST CDS_LIB mstr_discrete
J 0
(1450 1025);
PAINT ORANGE (1450 1025);
DISPLAY INVISIBLE (1450 1025);
FORCEADD TAP..7
(1250 775);
FORCEPROP 3 LASTPIN (1250 825) SIG_NAME P3E_CPU0_PE1_PCH_RXN<14>
J 0
(1260 835);
DISPLAY 0.659574 (1260 835);
PAINT MONO (1260 835);
DISPLAY INVISIBLE (1260 835);
FORCEPROP 1 LASTPIN (1250 825) BN 14
R 1
J 0
(1243 773);
DISPLAY 0.617021 (1243 773);
PAINT GREEN (1243 773);
FORCEPROP 1 LAST PATH I254
J 0
(1248 775);
DISPLAY 0.872340 (1248 775);
PAINT GREEN (1248 775);
DISPLAY INVISIBLE (1248 775);
FORCEPROP 2 LAST CDS_LIB mstr_standard
J 0
(1250 775);
PAINT ORANGE (1250 775);
DISPLAY INVISIBLE (1250 775);
FORCEPROP 1 LAST BODY_TYPE PLUMBING
J 0
(1300 775);
DISPLAY 2.276596 (1300 775);
PAINT GREEN (1300 775);
DISPLAY INVISIBLE (1300 775);
FORCEPROP 1 LAST HDL_TAP TRUE
J 0
(1570 645);
DISPLAY 2.276596 (1570 645);
PAINT GREEN (1570 645);
DISPLAY INVISIBLE (1570 645);
FORCEADD CAP..1
R 2
(1050 1025);
FORCEPROP 1 LAST MATERIAL X7R
J 2
(1000 925);
DISPLAY 0.617021 (1000 925);
PAINT SKYBLUE (1000 925);
FORCEPROP 1 LASTPIN (1050 925) $PN 2
J 2
(1040 905);
DISPLAY 0.617021 (1040 905);
PAINT ORANGE (1040 905);
FORCEPROP 1 LASTPIN (1050 1125) $PN 1
J 2
(1040 1105);
DISPLAY 0.617021 (1040 1105);
PAINT ORANGE (1040 1105);
FORCEPROP 1 LAST VOLTAGE 16V
J 2
(1000 1025);
DISPLAY 0.617021 (1000 1025);
PAINT SKYBLUE (1000 1025);
FORCEPROP 1 LAST PACK_TYPE 0402
J 2
(1000 825);
DISPLAY 0.617021 (1000 825);
PAINT SKYBLUE (1000 825);
FORCEPROP 1 LAST TOLERANCE 10%
J 2
(1000 975);
DISPLAY 0.617021 (1000 975);
PAINT SKYBLUE (1000 975);
FORCEPROP 1 LAST VALUE 0.22UF
J 2
(1000 1075);
DISPLAY 0.617021 (1000 1075);
PAINT SKYBLUE (1000 1075);
FORCEPROP 1 LAST PART_NUMBER A36096-155
J 2
(1000 875);
DISPLAY 0.617021 (1000 875);
PAINT BLUE (1000 875);
FORCEPROP 1 LAST LOCATION C3M1
J 2
(1000 1125);
DISPLAY 0.617021 (1000 1125);
PAINT AQUA (1000 1125);
FORCEPROP 0 LAST GROUP PCIE_UPLINK
J 0
(800 750);
DISPLAY 0.638298 (800 750);
PAINT BROWN (800 750);
DISPLAY BOTH (800 750);
FORCEPROP 2 LAST ROOM OCP_STEERING
J 2
(1050 1025);
PAINT MONO (1050 1025);
DISPLAY INVISIBLE (1050 1025);
FORCEPROP 1 LAST PATH I255
J 2
(1000 1175);
DISPLAY 0.978723 (1000 1175);
PAINT WHITE (1000 1175);
DISPLAY INVISIBLE (1000 1175);
FORCEPROP 2 LAST CDS_LOCATION C3M1
J 2
(1000 1125);
DISPLAY 0.617021 (1000 1125);
PAINT AQUA (1000 1125);
DISPLAY INVISIBLE (1000 1125);
FORCEPROP 2 LAST $SEC 1
J 0
(1000 1225);
DISPLAY 0.680851 (1000 1225);
PAINT MONO (1000 1225);
DISPLAY INVISIBLE (1000 1225);
FORCEPROP 2 LAST CDS_SEC 1
J 0
(1000 1225);
DISPLAY 1.021277 (1000 1225);
PAINT ORANGE (1000 1225);
DISPLAY INVISIBLE (1000 1225);
FORCEPROP 2 LAST CDS_LIB mstr_discrete
J 0
(1050 1025);
PAINT ORANGE (1050 1025);
DISPLAY INVISIBLE (1050 1025);
FORCEADD TAP..7
(1050 775);
FORCEPROP 3 LASTPIN (1050 825) SIG_NAME P3E_CPU0_PE1_PCH_RXN<15>
J 0
(1060 835);
DISPLAY 0.659574 (1060 835);
PAINT MONO (1060 835);
DISPLAY INVISIBLE (1060 835);
FORCEPROP 1 LASTPIN (1050 825) BN 15
R 1
J 0
(1043 773);
DISPLAY 0.617021 (1043 773);
PAINT GREEN (1043 773);
FORCEPROP 1 LAST PATH I256
J 0
(1048 775);
DISPLAY 0.872340 (1048 775);
PAINT GREEN (1048 775);
DISPLAY INVISIBLE (1048 775);
FORCEPROP 2 LAST CDS_LIB mstr_standard
J 0
(1050 775);
PAINT ORANGE (1050 775);
DISPLAY INVISIBLE (1050 775);
FORCEPROP 1 LAST BODY_TYPE PLUMBING
J 0
(1100 775);
DISPLAY 2.276596 (1100 775);
PAINT GREEN (1100 775);
DISPLAY INVISIBLE (1100 775);
FORCEPROP 1 LAST HDL_TAP TRUE
J 0
(1370 645);
DISPLAY 2.276596 (1370 645);
PAINT GREEN (1370 645);
DISPLAY INVISIBLE (1370 645);
FORCEADD CAP..1
R 2
(700 3650);
FORCEPROP 1 LAST LOCATION C7G19
J 2
(650 3750);
DISPLAY 0.617021 (650 3750);
PAINT AQUA (650 3750);
FORCEPROP 1 LAST PART_NUMBER A36096-155
J 2
(650 3500);
DISPLAY 0.617021 (650 3500);
PAINT BLUE (650 3500);
FORCEPROP 1 LAST VALUE 0.22UF
J 2
(650 3700);
DISPLAY 0.617021 (650 3700);
PAINT SKYBLUE (650 3700);
FORCEPROP 1 LAST TOLERANCE 10%
J 2
(650 3600);
DISPLAY 0.617021 (650 3600);
PAINT SKYBLUE (650 3600);
FORCEPROP 1 LAST PACK_TYPE 0402
J 2
(650 3450);
DISPLAY 0.617021 (650 3450);
PAINT SKYBLUE (650 3450);
FORCEPROP 1 LAST VOLTAGE 16V
J 2
(650 3650);
DISPLAY 0.617021 (650 3650);
PAINT SKYBLUE (650 3650);
FORCEPROP 1 LAST MATERIAL X7R
J 2
(650 3550);
DISPLAY 0.617021 (650 3550);
PAINT SKYBLUE (650 3550);
FORCEPROP 1 LASTPIN (700 3550) $PN 2
J 2
(690 3530);
DISPLAY 0.617021 (690 3530);
PAINT ORANGE (690 3530);
FORCEPROP 1 LASTPIN (700 3750) $PN 1
J 2
(690 3730);
DISPLAY 0.617021 (690 3730);
PAINT ORANGE (690 3730);
FORCEPROP 2 LAST SEC_TYPE 0402
J 0
(650 3850);
DISPLAY 1.021277 (650 3850);
PAINT ORANGE (650 3850);
DISPLAY INVISIBLE (650 3850);
FORCEPROP 2 LAST CDS_LIB mstr_discrete
J 0
(700 3650);
PAINT ORANGE (700 3650);
DISPLAY INVISIBLE (700 3650);
FORCEPROP 2 LAST SEC 1
J 0
(650 3850);
DISPLAY 0.680851 (650 3850);
PAINT MONO (650 3850);
DISPLAY INVISIBLE (650 3850);
FORCEPROP 2 LAST CDS_LOCATION C7G19
J 2
(650 3750);
DISPLAY 0.617021 (650 3750);
PAINT AQUA (650 3750);
DISPLAY INVISIBLE (650 3750);
FORCEPROP 2 LAST ROOM OCP_STEERING
J 2
(700 3650);
PAINT MONO (700 3650);
DISPLAY INVISIBLE (700 3650);
FORCEPROP 0 LAST CDS_SEC 1
J 0
(650 3800);
PAINT MONO (650 3800);
DISPLAY INVISIBLE (650 3800);
FORCEPROP 1 LAST PATH I257
J 2
(650 3800);
DISPLAY 0.978723 (650 3800);
PAINT WHITE (650 3800);
DISPLAY INVISIBLE (650 3800);
FORCEADD CAP..1
R 2
(650 4650);
FORCEPROP 1 LASTPIN (650 4750) $PN 1
J 2
(640 4730);
DISPLAY 0.617021 (640 4730);
PAINT ORANGE (640 4730);
FORCEPROP 1 LASTPIN (650 4550) $PN 2
J 2
(640 4530);
DISPLAY 0.617021 (640 4530);
PAINT ORANGE (640 4530);
FORCEPROP 1 LAST MATERIAL X7R
J 2
(600 4550);
DISPLAY 0.617021 (600 4550);
PAINT SKYBLUE (600 4550);
FORCEPROP 1 LAST VOLTAGE 16V
J 2
(600 4650);
DISPLAY 0.617021 (600 4650);
PAINT SKYBLUE (600 4650);
FORCEPROP 1 LAST PACK_TYPE 0402
J 2
(600 4450);
DISPLAY 0.617021 (600 4450);
PAINT SKYBLUE (600 4450);
FORCEPROP 1 LAST TOLERANCE 10%
J 2
(600 4600);
DISPLAY 0.617021 (600 4600);
PAINT SKYBLUE (600 4600);
FORCEPROP 1 LAST VALUE 0.22UF
J 2
(600 4700);
DISPLAY 0.617021 (600 4700);
PAINT SKYBLUE (600 4700);
FORCEPROP 1 LAST PART_NUMBER A36096-155
J 2
(600 4500);
DISPLAY 0.617021 (600 4500);
PAINT BLUE (600 4500);
FORCEPROP 1 LAST LOCATION C7G20
J 2
(600 4750);
DISPLAY 0.617021 (600 4750);
PAINT AQUA (600 4750);
FORCEPROP 0 LAST CDS_SEC 1
J 0
(600 4800);
PAINT MONO (600 4800);
DISPLAY INVISIBLE (600 4800);
FORCEPROP 2 LAST ROOM OCP_STEERING
J 2
(650 4650);
PAINT MONO (650 4650);
DISPLAY INVISIBLE (650 4650);
FORCEPROP 2 LAST CDS_LOCATION C7G20
J 2
(600 4750);
DISPLAY 0.617021 (600 4750);
PAINT AQUA (600 4750);
DISPLAY INVISIBLE (600 4750);
FORCEPROP 2 LAST SEC 1
J 0
(600 4850);
DISPLAY 0.680851 (600 4850);
PAINT MONO (600 4850);
DISPLAY INVISIBLE (600 4850);
FORCEPROP 2 LAST CDS_LIB mstr_discrete
J 0
(650 4650);
PAINT ORANGE (650 4650);
DISPLAY INVISIBLE (650 4650);
FORCEPROP 2 LAST SEC_TYPE 0402
J 0
(600 4850);
DISPLAY 1.021277 (600 4850);
PAINT ORANGE (600 4850);
DISPLAY INVISIBLE (600 4850);
FORCEPROP 1 LAST PATH I258
J 2
(600 4800);
DISPLAY 0.978723 (600 4800);
PAINT WHITE (600 4800);
DISPLAY INVISIBLE (600 4800);
FORCEADD TAP..7
(50 4100);
FORCEPROP 3 LASTPIN (50 4150) SIG_NAME P3E_CPU0_PE2_SS_C_TXP<11>
J 0
(60 4160);
DISPLAY 0.659574 (60 4160);
PAINT MONO (60 4160);
DISPLAY INVISIBLE (60 4160);
FORCEPROP 1 LASTPIN (50 4150) BN 11
R 1
J 0
(43 4098);
DISPLAY 0.617021 (43 4098);
PAINT GREEN (43 4098);
FORCEPROP 1 LAST PATH I26
J 0
(48 4100);
DISPLAY 0.872340 (48 4100);
PAINT GREEN (48 4100);
DISPLAY INVISIBLE (48 4100);
FORCEPROP 2 LAST CDS_LIB mstr_standard
J 0
(50 4100);
PAINT ORANGE (50 4100);
DISPLAY INVISIBLE (50 4100);
FORCEPROP 1 LAST BODY_TYPE PLUMBING
J 0
(100 4100);
DISPLAY 2.276596 (100 4100);
PAINT GREEN (100 4100);
DISPLAY INVISIBLE (100 4100);
FORCEPROP 1 LAST HDL_TAP TRUE
J 0
(370 3970);
DISPLAY 2.276596 (370 3970);
PAINT GREEN (370 3970);
DISPLAY INVISIBLE (370 3970);
FORCEADD CAP..1
R 2
(-150 4650);
FORCEPROP 1 LASTPIN (-150 4750) $PN 1
J 2
(-160 4730);
DISPLAY 0.617021 (-160 4730);
PAINT ORANGE (-160 4730);
FORCEPROP 1 LASTPIN (-150 4550) $PN 2
J 2
(-160 4530);
DISPLAY 0.617021 (-160 4530);
PAINT ORANGE (-160 4530);
FORCEPROP 1 LAST MATERIAL X7R
J 2
(-200 4550);
DISPLAY 0.617021 (-200 4550);
PAINT SKYBLUE (-200 4550);
FORCEPROP 1 LAST VOLTAGE 16V
J 2
(-200 4650);
DISPLAY 0.617021 (-200 4650);
PAINT SKYBLUE (-200 4650);
FORCEPROP 1 LAST PACK_TYPE 0402
J 2
(-200 4450);
DISPLAY 0.617021 (-200 4450);
PAINT SKYBLUE (-200 4450);
FORCEPROP 1 LAST TOLERANCE 10%
J 2
(-200 4600);
DISPLAY 0.617021 (-200 4600);
PAINT SKYBLUE (-200 4600);
FORCEPROP 1 LAST VALUE 0.22UF
J 2
(-200 4700);
DISPLAY 0.617021 (-200 4700);
PAINT SKYBLUE (-200 4700);
FORCEPROP 1 LAST PART_NUMBER A36096-155
J 2
(-200 4500);
DISPLAY 0.617021 (-200 4500);
PAINT BLUE (-200 4500);
FORCEPROP 1 LAST LOCATION C7G11
J 2
(-200 4750);
DISPLAY 0.617021 (-200 4750);
PAINT AQUA (-200 4750);
FORCEPROP 2 LAST ROOM OCP_STEERING
J 2
(-150 4650);
PAINT MONO (-150 4650);
DISPLAY INVISIBLE (-150 4650);
FORCEPROP 1 LAST PATH I27
J 2
(-200 4800);
DISPLAY 0.978723 (-200 4800);
PAINT WHITE (-200 4800);
DISPLAY INVISIBLE (-200 4800);
FORCEPROP 2 LAST CDS_LOCATION C7G11
J 2
(-200 4750);
DISPLAY 0.617021 (-200 4750);
PAINT AQUA (-200 4750);
DISPLAY INVISIBLE (-200 4750);
FORCEPROP 2 LAST SEC 1
J 0
(-200 4850);
DISPLAY 0.680851 (-200 4850);
PAINT MONO (-200 4850);
DISPLAY INVISIBLE (-200 4850);
FORCEPROP 2 LAST CDS_LIB mstr_discrete
J 0
(-150 4650);
PAINT ORANGE (-150 4650);
DISPLAY INVISIBLE (-150 4650);
FORCEPROP 2 LAST SEC_TYPE 0402
J 0
(-200 4850);
DISPLAY 1.021277 (-200 4850);
PAINT ORANGE (-200 4850);
DISPLAY INVISIBLE (-200 4850);
FORCEADD CAP..1
R 2
(50 4350);
FORCEPROP 1 LASTPIN (50 4450) $PN 1
J 2
(40 4430);
DISPLAY 0.617021 (40 4430);
PAINT ORANGE (40 4430);
FORCEPROP 1 LASTPIN (50 4250) $PN 2
J 2
(40 4230);
DISPLAY 0.617021 (40 4230);
PAINT ORANGE (40 4230);
FORCEPROP 1 LAST MATERIAL X7R
J 2
(0 4250);
DISPLAY 0.617021 (0 4250);
PAINT SKYBLUE (0 4250);
FORCEPROP 1 LAST VOLTAGE 16V
J 2
(0 4350);
DISPLAY 0.617021 (0 4350);
PAINT SKYBLUE (0 4350);
FORCEPROP 1 LAST PACK_TYPE 0402
J 2
(0 4150);
DISPLAY 0.617021 (0 4150);
PAINT SKYBLUE (0 4150);
FORCEPROP 1 LAST TOLERANCE 10%
J 2
(0 4300);
DISPLAY 0.617021 (0 4300);
PAINT SKYBLUE (0 4300);
FORCEPROP 1 LAST VALUE 0.22UF
J 2
(0 4400);
DISPLAY 0.617021 (0 4400);
PAINT SKYBLUE (0 4400);
FORCEPROP 1 LAST PART_NUMBER A36096-155
J 2
(0 4200);
DISPLAY 0.617021 (0 4200);
PAINT BLUE (0 4200);
FORCEPROP 1 LAST LOCATION C7G14
J 2
(0 4450);
DISPLAY 0.617021 (0 4450);
PAINT AQUA (0 4450);
FORCEPROP 2 LAST ROOM OCP_STEERING
J 2
(50 4350);
PAINT MONO (50 4350);
DISPLAY INVISIBLE (50 4350);
FORCEPROP 1 LAST PATH I28
J 2
(0 4500);
DISPLAY 0.978723 (0 4500);
PAINT WHITE (0 4500);
DISPLAY INVISIBLE (0 4500);
FORCEPROP 2 LAST CDS_LOCATION C7G14
J 2
(0 4450);
DISPLAY 0.617021 (0 4450);
PAINT AQUA (0 4450);
DISPLAY INVISIBLE (0 4450);
FORCEPROP 2 LAST SEC 1
J 0
(0 4550);
DISPLAY 0.680851 (0 4550);
PAINT MONO (0 4550);
DISPLAY INVISIBLE (0 4550);
FORCEPROP 2 LAST CDS_LIB mstr_discrete
J 0
(50 4350);
PAINT ORANGE (50 4350);
DISPLAY INVISIBLE (50 4350);
FORCEPROP 2 LAST SEC_TYPE 0402
J 0
(0 4550);
DISPLAY 1.021277 (0 4550);
PAINT ORANGE (0 4550);
DISPLAY INVISIBLE (0 4550);
FORCEADD TAP..7
(300 3100);
FORCEPROP 3 LASTPIN (300 3150) SIG_NAME P3E_CPU0_PE2_SS_C_TXN<10>
J 0
(310 3160);
DISPLAY 0.659574 (310 3160);
PAINT MONO (310 3160);
DISPLAY INVISIBLE (310 3160);
FORCEPROP 1 LASTPIN (300 3150) BN 10
R 1
J 0
(293 3098);
DISPLAY 0.617021 (293 3098);
PAINT GREEN (293 3098);
FORCEPROP 1 LAST PATH I29
J 0
(298 3100);
DISPLAY 0.872340 (298 3100);
PAINT GREEN (298 3100);
DISPLAY INVISIBLE (298 3100);
FORCEPROP 2 LAST CDS_LIB mstr_standard
J 0
(300 3100);
PAINT ORANGE (300 3100);
DISPLAY INVISIBLE (300 3100);
FORCEPROP 1 LAST BODY_TYPE PLUMBING
J 0
(350 3100);
DISPLAY 2.276596 (350 3100);
PAINT GREEN (350 3100);
DISPLAY INVISIBLE (350 3100);
FORCEPROP 1 LAST HDL_TAP TRUE
J 0
(620 2970);
DISPLAY 2.276596 (620 2970);
PAINT GREEN (620 2970);
DISPLAY INVISIBLE (620 2970);
FORCEADD OFFPAGE..1
(-875 3950);
FORCEPROP 2 LAST $XR0 31 
J 0
(-1096 3950);
DISPLAY 0.638298 (-1096 3950);
PAINT MONO (-1096 3950);
FORCEPROP 2 LAST PATH I3
J 0
(-1075 4000);
DISPLAY 1.021277 (-1075 4000);
PAINT ORANGE (-1075 4000);
DISPLAY INVISIBLE (-1075 4000);
FORCEPROP 2 LAST CDS_LIB mstr_standard
J 0
(-875 3950);
PAINT ORANGE (-875 3950);
DISPLAY INVISIBLE (-875 3950);
FORCEPROP 1 LAST OFFPAGE TRUE
J 0
(-555 3820);
PAINT GREEN (-555 3820);
DISPLAY INVISIBLE (-555 3820);
FORCEPROP 1 LAST COMMENT_BODY TRUE
J 0
(-755 3850);
DISPLAY 2.276596 (-755 3850);
PAINT GREEN (-755 3850);
DISPLAY INVISIBLE (-755 3850);
FORCEADD TAP..7
(500 3100);
FORCEPROP 3 LASTPIN (500 3150) SIG_NAME P3E_CPU0_PE2_SS_C_TXN<9>
J 0
(510 3160);
DISPLAY 0.659574 (510 3160);
PAINT MONO (510 3160);
DISPLAY INVISIBLE (510 3160);
FORCEPROP 1 LASTPIN (500 3150) BN 9
R 1
J 0
(493 3098);
DISPLAY 0.617021 (493 3098);
PAINT GREEN (493 3098);
FORCEPROP 1 LAST PATH I30
J 0
(498 3100);
DISPLAY 0.872340 (498 3100);
PAINT GREEN (498 3100);
DISPLAY INVISIBLE (498 3100);
FORCEPROP 2 LAST CDS_LIB mstr_standard
J 0
(500 3100);
PAINT ORANGE (500 3100);
DISPLAY INVISIBLE (500 3100);
FORCEPROP 1 LAST BODY_TYPE PLUMBING
J 0
(550 3100);
DISPLAY 2.276596 (550 3100);
PAINT GREEN (550 3100);
DISPLAY INVISIBLE (550 3100);
FORCEPROP 1 LAST HDL_TAP TRUE
J 0
(820 2970);
DISPLAY 2.276596 (820 2970);
PAINT GREEN (820 2970);
DISPLAY INVISIBLE (820 2970);
FORCEADD CAP..1
R 2
(300 3650);
FORCEPROP 1 LASTPIN (300 3750) $PN 1
J 2
(290 3730);
DISPLAY 0.617021 (290 3730);
PAINT ORANGE (290 3730);
FORCEPROP 1 LASTPIN (300 3550) $PN 2
J 2
(290 3530);
DISPLAY 0.617021 (290 3530);
PAINT ORANGE (290 3530);
FORCEPROP 1 LAST PACK_TYPE 0402
J 2
(250 3450);
DISPLAY 0.617021 (250 3450);
PAINT SKYBLUE (250 3450);
FORCEPROP 1 LAST PART_NUMBER A36096-155
J 2
(250 3500);
DISPLAY 0.617021 (250 3500);
PAINT BLUE (250 3500);
FORCEPROP 1 LAST MATERIAL X7R
J 2
(250 3550);
DISPLAY 0.617021 (250 3550);
PAINT SKYBLUE (250 3550);
FORCEPROP 1 LAST TOLERANCE 10%
J 2
(250 3600);
DISPLAY 0.617021 (250 3600);
PAINT SKYBLUE (250 3600);
FORCEPROP 1 LAST VOLTAGE 16V
J 2
(250 3650);
DISPLAY 0.617021 (250 3650);
PAINT SKYBLUE (250 3650);
FORCEPROP 1 LAST VALUE 0.22UF
J 2
(250 3700);
DISPLAY 0.617021 (250 3700);
PAINT SKYBLUE (250 3700);
FORCEPROP 1 LAST LOCATION C7G16
J 2
(250 3750);
DISPLAY 0.617021 (250 3750);
PAINT AQUA (250 3750);
FORCEPROP 2 LAST ROOM OCP_STEERING
J 2
(300 3650);
PAINT MONO (300 3650);
DISPLAY INVISIBLE (300 3650);
FORCEPROP 1 LAST PATH I31
J 2
(250 3800);
DISPLAY 0.978723 (250 3800);
PAINT WHITE (250 3800);
DISPLAY INVISIBLE (250 3800);
FORCEPROP 2 LAST CDS_LOCATION C7G16
J 2
(250 3750);
DISPLAY 0.617021 (250 3750);
PAINT AQUA (250 3750);
DISPLAY INVISIBLE (250 3750);
FORCEPROP 2 LAST SEC 1
J 0
(250 3850);
DISPLAY 0.680851 (250 3850);
PAINT MONO (250 3850);
DISPLAY INVISIBLE (250 3850);
FORCEPROP 2 LAST CDS_LIB mstr_discrete
J 0
(300 3650);
PAINT ORANGE (300 3650);
DISPLAY INVISIBLE (300 3650);
FORCEPROP 2 LAST SEC_TYPE 0402
J 0
(250 3850);
DISPLAY 1.021277 (250 3850);
PAINT ORANGE (250 3850);
DISPLAY INVISIBLE (250 3850);
FORCEADD CAP..1
R 2
(500 3350);
FORCEPROP 1 LASTPIN (500 3450) $PN 1
J 2
(490 3430);
DISPLAY 0.617021 (490 3430);
PAINT ORANGE (490 3430);
FORCEPROP 1 LASTPIN (500 3250) $PN 2
J 2
(490 3230);
DISPLAY 0.617021 (490 3230);
PAINT ORANGE (490 3230);
FORCEPROP 1 LAST VOLTAGE 16V
J 2
(450 3350);
DISPLAY 0.617021 (450 3350);
PAINT SKYBLUE (450 3350);
FORCEPROP 1 LAST VALUE 0.22UF
J 2
(450 3400);
DISPLAY 0.617021 (450 3400);
PAINT SKYBLUE (450 3400);
FORCEPROP 1 LAST LOCATION C7G18
J 2
(450 3450);
DISPLAY 0.617021 (450 3450);
PAINT AQUA (450 3450);
FORCEPROP 1 LAST PACK_TYPE 0402
J 2
(450 3150);
DISPLAY 0.617021 (450 3150);
PAINT SKYBLUE (450 3150);
FORCEPROP 1 LAST PART_NUMBER A36096-155
J 2
(450 3200);
DISPLAY 0.617021 (450 3200);
PAINT BLUE (450 3200);
FORCEPROP 1 LAST MATERIAL X7R
J 2
(450 3250);
DISPLAY 0.617021 (450 3250);
PAINT SKYBLUE (450 3250);
FORCEPROP 1 LAST TOLERANCE 10%
J 2
(450 3300);
DISPLAY 0.617021 (450 3300);
PAINT SKYBLUE (450 3300);
FORCEPROP 2 LAST ROOM OCP_STEERING
J 2
(500 3350);
PAINT MONO (500 3350);
DISPLAY INVISIBLE (500 3350);
FORCEPROP 1 LAST PATH I32
J 2
(450 3500);
DISPLAY 0.978723 (450 3500);
PAINT WHITE (450 3500);
DISPLAY INVISIBLE (450 3500);
FORCEPROP 2 LAST CDS_LOCATION C7G18
J 2
(450 3450);
DISPLAY 0.617021 (450 3450);
PAINT AQUA (450 3450);
DISPLAY INVISIBLE (450 3450);
FORCEPROP 2 LAST SEC 1
J 0
(450 3550);
DISPLAY 0.680851 (450 3550);
PAINT MONO (450 3550);
DISPLAY INVISIBLE (450 3550);
FORCEPROP 2 LAST CDS_LIB mstr_discrete
J 0
(500 3350);
PAINT ORANGE (500 3350);
DISPLAY INVISIBLE (500 3350);
FORCEPROP 2 LAST SEC_TYPE 0402
J 0
(450 3550);
DISPLAY 1.021277 (450 3550);
PAINT ORANGE (450 3550);
DISPLAY INVISIBLE (450 3550);
FORCEADD TAP..7
(700 3100);
FORCEPROP 3 LASTPIN (700 3150) SIG_NAME P3E_CPU0_PE2_SS_C_TXN<8>
J 0
(710 3160);
DISPLAY 0.659574 (710 3160);
PAINT MONO (710 3160);
DISPLAY INVISIBLE (710 3160);
FORCEPROP 1 LASTPIN (700 3150) BN 8
R 1
J 0
(693 3098);
DISPLAY 0.617021 (693 3098);
PAINT GREEN (693 3098);
FORCEPROP 1 LAST PATH I33
J 0
(698 3100);
DISPLAY 0.872340 (698 3100);
PAINT GREEN (698 3100);
DISPLAY INVISIBLE (698 3100);
FORCEPROP 2 LAST CDS_LIB mstr_standard
J 0
(700 3100);
PAINT ORANGE (700 3100);
DISPLAY INVISIBLE (700 3100);
FORCEPROP 1 LAST BODY_TYPE PLUMBING
J 0
(750 3100);
DISPLAY 2.276596 (750 3100);
PAINT GREEN (750 3100);
DISPLAY INVISIBLE (750 3100);
FORCEPROP 1 LAST HDL_TAP TRUE
J 0
(1020 2970);
DISPLAY 2.276596 (1020 2970);
PAINT GREEN (1020 2970);
DISPLAY INVISIBLE (1020 2970);
FORCEADD TAP..7
(925 3100);
FORCEPROP 3 LASTPIN (925 3150) SIG_NAME P3E_CPU0_PE2_SS_C_TXN<7>
J 0
(935 3160);
DISPLAY 0.659574 (935 3160);
PAINT MONO (935 3160);
DISPLAY INVISIBLE (935 3160);
FORCEPROP 1 LASTPIN (925 3150) BN 7
R 1
J 0
(918 3098);
DISPLAY 0.617021 (918 3098);
PAINT GREEN (918 3098);
FORCEPROP 1 LAST PATH I35
J 0
(923 3100);
DISPLAY 0.872340 (923 3100);
PAINT GREEN (923 3100);
DISPLAY INVISIBLE (923 3100);
FORCEPROP 2 LAST CDS_LIB mstr_standard
J 0
(925 3100);
PAINT ORANGE (925 3100);
DISPLAY INVISIBLE (925 3100);
FORCEPROP 1 LAST BODY_TYPE PLUMBING
J 0
(975 3100);
DISPLAY 2.276596 (975 3100);
PAINT GREEN (975 3100);
DISPLAY INVISIBLE (975 3100);
FORCEPROP 1 LAST HDL_TAP TRUE
J 0
(1245 2970);
DISPLAY 2.276596 (1245 2970);
PAINT GREEN (1245 2970);
DISPLAY INVISIBLE (1245 2970);
FORCEADD TAP..7
(1125 3100);
FORCEPROP 3 LASTPIN (1125 3150) SIG_NAME P3E_CPU0_PE2_SS_C_TXN<6>
J 0
(1135 3160);
DISPLAY 0.659574 (1135 3160);
PAINT MONO (1135 3160);
DISPLAY INVISIBLE (1135 3160);
FORCEPROP 1 LASTPIN (1125 3150) BN 6
R 1
J 0
(1118 3098);
DISPLAY 0.617021 (1118 3098);
PAINT GREEN (1118 3098);
FORCEPROP 1 LAST PATH I36
J 0
(1123 3100);
DISPLAY 0.872340 (1123 3100);
PAINT GREEN (1123 3100);
DISPLAY INVISIBLE (1123 3100);
FORCEPROP 2 LAST CDS_LIB mstr_standard
J 0
(1125 3100);
PAINT ORANGE (1125 3100);
DISPLAY INVISIBLE (1125 3100);
FORCEPROP 1 LAST BODY_TYPE PLUMBING
J 0
(1175 3100);
DISPLAY 2.276596 (1175 3100);
PAINT GREEN (1175 3100);
DISPLAY INVISIBLE (1175 3100);
FORCEPROP 1 LAST HDL_TAP TRUE
J 0
(1445 2970);
DISPLAY 2.276596 (1445 2970);
PAINT GREEN (1445 2970);
DISPLAY INVISIBLE (1445 2970);
FORCEADD CAP..1
R 2
(925 3350);
FORCEPROP 1 LASTPIN (925 3250) $PN 2
J 2
(915 3230);
DISPLAY 0.617021 (915 3230);
PAINT ORANGE (915 3230);
FORCEPROP 1 LAST MATERIAL X7R
J 2
(875 3250);
DISPLAY 0.617021 (875 3250);
PAINT SKYBLUE (875 3250);
FORCEPROP 1 LAST VOLTAGE 16V
J 2
(875 3350);
DISPLAY 0.617021 (875 3350);
PAINT SKYBLUE (875 3350);
FORCEPROP 1 LAST PACK_TYPE 0402
J 2
(875 3150);
DISPLAY 0.617021 (875 3150);
PAINT SKYBLUE (875 3150);
FORCEPROP 1 LAST TOLERANCE 10%
J 2
(875 3300);
DISPLAY 0.617021 (875 3300);
PAINT SKYBLUE (875 3300);
FORCEPROP 1 LAST LOCATION C7G22
J 2
(875 3450);
DISPLAY 0.617021 (875 3450);
PAINT AQUA (875 3450);
FORCEPROP 1 LAST VALUE 0.22UF
J 2
(875 3400);
DISPLAY 0.617021 (875 3400);
PAINT SKYBLUE (875 3400);
FORCEPROP 1 LASTPIN (925 3450) $PN 1
J 2
(915 3430);
DISPLAY 0.617021 (915 3430);
PAINT ORANGE (915 3430);
FORCEPROP 1 LAST PART_NUMBER A36096-155
J 2
(875 3200);
DISPLAY 0.617021 (875 3200);
PAINT BLUE (875 3200);
FORCEPROP 2 LAST ROOM OCP_STEERING
J 2
(925 3350);
PAINT MONO (925 3350);
DISPLAY INVISIBLE (925 3350);
FORCEPROP 1 LAST PATH I37
J 2
(875 3500);
DISPLAY 0.978723 (875 3500);
PAINT WHITE (875 3500);
DISPLAY INVISIBLE (875 3500);
FORCEPROP 2 LAST CDS_LOCATION C7G22
J 2
(875 3450);
DISPLAY 0.617021 (875 3450);
PAINT AQUA (875 3450);
DISPLAY INVISIBLE (875 3450);
FORCEPROP 2 LAST SEC 1
J 0
(875 3550);
DISPLAY 0.680851 (875 3550);
PAINT MONO (875 3550);
DISPLAY INVISIBLE (875 3550);
FORCEPROP 2 LAST SEC_TYPE 0402
J 0
(875 3550);
DISPLAY 1.021277 (875 3550);
PAINT ORANGE (875 3550);
DISPLAY INVISIBLE (875 3550);
FORCEPROP 2 LAST CDS_LIB mstr_discrete
J 0
(925 3350);
PAINT ORANGE (925 3350);
DISPLAY INVISIBLE (925 3350);
FORCEADD TAP..3
(300 3900);
FORCEPROP 3 LASTPIN (300 3850) SIG_NAME P3E_CPU0_PE2_SS_TXN<10>
J 0
(310 3860);
DISPLAY 0.659574 (310 3860);
PAINT MONO (310 3860);
DISPLAY INVISIBLE (310 3860);
FORCEPROP 1 LASTPIN (300 3850) BN 10
R 1
J 0
(293 3838);
DISPLAY 0.617021 (293 3838);
PAINT GREEN (293 3838);
FORCEPROP 1 LAST PATH I38
J 0
(298 3900);
DISPLAY 0.872340 (298 3900);
PAINT GREEN (298 3900);
DISPLAY INVISIBLE (298 3900);
FORCEPROP 2 LAST CDS_LIB mstr_standard
J 0
(300 3900);
PAINT ORANGE (300 3900);
DISPLAY INVISIBLE (300 3900);
FORCEPROP 1 LAST BODY_TYPE PLUMBING
J 0
(350 3850);
DISPLAY 2.276596 (350 3850);
PAINT GREEN (350 3850);
DISPLAY INVISIBLE (350 3850);
FORCEPROP 1 LAST HDL_TAP TRUE
J 0
(620 3770);
DISPLAY 2.276596 (620 3770);
PAINT GREEN (620 3770);
DISPLAY INVISIBLE (620 3770);
FORCEADD TAP..7
(250 4100);
FORCEPROP 3 LASTPIN (250 4150) SIG_NAME P3E_CPU0_PE2_SS_C_TXP<10>
J 0
(260 4160);
DISPLAY 0.659574 (260 4160);
PAINT MONO (260 4160);
DISPLAY INVISIBLE (260 4160);
FORCEPROP 1 LASTPIN (250 4150) BN 10
R 1
J 0
(243 4098);
DISPLAY 0.617021 (243 4098);
PAINT GREEN (243 4098);
FORCEPROP 1 LAST PATH I39
J 0
(248 4100);
DISPLAY 0.872340 (248 4100);
PAINT GREEN (248 4100);
DISPLAY INVISIBLE (248 4100);
FORCEPROP 2 LAST CDS_LIB mstr_standard
J 0
(250 4100);
PAINT ORANGE (250 4100);
DISPLAY INVISIBLE (250 4100);
FORCEPROP 1 LAST BODY_TYPE PLUMBING
J 0
(300 4100);
DISPLAY 2.276596 (300 4100);
PAINT GREEN (300 4100);
DISPLAY INVISIBLE (300 4100);
FORCEPROP 1 LAST HDL_TAP TRUE
J 0
(570 3970);
DISPLAY 2.276596 (570 3970);
PAINT GREEN (570 3970);
DISPLAY INVISIBLE (570 3970);
FORCEADD TAP..7
(-700 3100);
FORCEPROP 3 LASTPIN (-700 3150) SIG_NAME P3E_CPU0_PE2_SS_C_TXN<15>
J 0
(-690 3160);
DISPLAY 0.659574 (-690 3160);
PAINT MONO (-690 3160);
DISPLAY INVISIBLE (-690 3160);
FORCEPROP 1 LASTPIN (-700 3150) BN 15
R 1
J 0
(-707 3098);
DISPLAY 0.617021 (-707 3098);
PAINT GREEN (-707 3098);
FORCEPROP 1 LAST PATH I4
J 0
(-702 3100);
DISPLAY 0.872340 (-702 3100);
PAINT GREEN (-702 3100);
DISPLAY INVISIBLE (-702 3100);
FORCEPROP 2 LAST CDS_LIB mstr_standard
J 0
(-700 3100);
PAINT ORANGE (-700 3100);
DISPLAY INVISIBLE (-700 3100);
FORCEPROP 1 LAST BODY_TYPE PLUMBING
J 0
(-650 3100);
DISPLAY 2.276596 (-650 3100);
PAINT GREEN (-650 3100);
DISPLAY INVISIBLE (-650 3100);
FORCEPROP 1 LAST HDL_TAP TRUE
J 0
(-380 2970);
DISPLAY 2.276596 (-380 2970);
PAINT GREEN (-380 2970);
DISPLAY INVISIBLE (-380 2970);
FORCEADD TAP..3
(500 3900);
FORCEPROP 3 LASTPIN (500 3850) SIG_NAME P3E_CPU0_PE2_SS_TXN<9>
J 0
(510 3860);
DISPLAY 0.659574 (510 3860);
PAINT MONO (510 3860);
DISPLAY INVISIBLE (510 3860);
FORCEPROP 1 LASTPIN (500 3850) BN 9
R 1
J 0
(493 3838);
DISPLAY 0.617021 (493 3838);
PAINT GREEN (493 3838);
FORCEPROP 1 LAST PATH I40
J 0
(498 3900);
DISPLAY 0.872340 (498 3900);
PAINT GREEN (498 3900);
DISPLAY INVISIBLE (498 3900);
FORCEPROP 2 LAST CDS_LIB mstr_standard
J 0
(500 3900);
PAINT ORANGE (500 3900);
DISPLAY INVISIBLE (500 3900);
FORCEPROP 1 LAST BODY_TYPE PLUMBING
J 0
(550 3850);
DISPLAY 2.276596 (550 3850);
PAINT GREEN (550 3850);
DISPLAY INVISIBLE (550 3850);
FORCEPROP 1 LAST HDL_TAP TRUE
J 0
(820 3770);
DISPLAY 2.276596 (820 3770);
PAINT GREEN (820 3770);
DISPLAY INVISIBLE (820 3770);
FORCEADD TAP..7
(450 4100);
FORCEPROP 3 LASTPIN (450 4150) SIG_NAME P3E_CPU0_PE2_SS_C_TXP<9>
J 0
(460 4160);
DISPLAY 0.659574 (460 4160);
PAINT MONO (460 4160);
DISPLAY INVISIBLE (460 4160);
FORCEPROP 1 LASTPIN (450 4150) BN 9
R 1
J 0
(443 4098);
DISPLAY 0.617021 (443 4098);
PAINT GREEN (443 4098);
FORCEPROP 1 LAST PATH I41
J 0
(448 4100);
DISPLAY 0.872340 (448 4100);
PAINT GREEN (448 4100);
DISPLAY INVISIBLE (448 4100);
FORCEPROP 2 LAST CDS_LIB mstr_standard
J 0
(450 4100);
PAINT ORANGE (450 4100);
DISPLAY INVISIBLE (450 4100);
FORCEPROP 1 LAST BODY_TYPE PLUMBING
J 0
(500 4100);
DISPLAY 2.276596 (500 4100);
PAINT GREEN (500 4100);
DISPLAY INVISIBLE (500 4100);
FORCEPROP 1 LAST HDL_TAP TRUE
J 0
(770 3970);
DISPLAY 2.276596 (770 3970);
PAINT GREEN (770 3970);
DISPLAY INVISIBLE (770 3970);
FORCEADD TAP..3
(700 3900);
FORCEPROP 3 LASTPIN (700 3850) SIG_NAME P3E_CPU0_PE2_SS_TXN<8>
J 0
(710 3860);
DISPLAY 0.659574 (710 3860);
PAINT MONO (710 3860);
DISPLAY INVISIBLE (710 3860);
FORCEPROP 1 LASTPIN (700 3850) BN 8
R 1
J 0
(693 3838);
DISPLAY 0.617021 (693 3838);
PAINT GREEN (693 3838);
FORCEPROP 1 LAST PATH I42
J 0
(698 3900);
DISPLAY 0.872340 (698 3900);
PAINT GREEN (698 3900);
DISPLAY INVISIBLE (698 3900);
FORCEPROP 2 LAST CDS_LIB mstr_standard
J 0
(700 3900);
PAINT ORANGE (700 3900);
DISPLAY INVISIBLE (700 3900);
FORCEPROP 1 LAST BODY_TYPE PLUMBING
J 0
(750 3850);
DISPLAY 2.276596 (750 3850);
PAINT GREEN (750 3850);
DISPLAY INVISIBLE (750 3850);
FORCEPROP 1 LAST HDL_TAP TRUE
J 0
(1020 3770);
DISPLAY 2.276596 (1020 3770);
PAINT GREEN (1020 3770);
DISPLAY INVISIBLE (1020 3770);
FORCEADD TAP..7
(650 4100);
FORCEPROP 3 LASTPIN (650 4150) SIG_NAME P3E_CPU0_PE2_SS_C_TXP<8>
J 0
(660 4160);
DISPLAY 0.659574 (660 4160);
PAINT MONO (660 4160);
DISPLAY INVISIBLE (660 4160);
FORCEPROP 1 LASTPIN (650 4150) BN 8
R 1
J 0
(643 4098);
DISPLAY 0.617021 (643 4098);
PAINT GREEN (643 4098);
FORCEPROP 1 LAST PATH I43
J 0
(648 4100);
DISPLAY 0.872340 (648 4100);
PAINT GREEN (648 4100);
DISPLAY INVISIBLE (648 4100);
FORCEPROP 2 LAST CDS_LIB mstr_standard
J 0
(650 4100);
PAINT ORANGE (650 4100);
DISPLAY INVISIBLE (650 4100);
FORCEPROP 1 LAST BODY_TYPE PLUMBING
J 0
(700 4100);
DISPLAY 2.276596 (700 4100);
PAINT GREEN (700 4100);
DISPLAY INVISIBLE (700 4100);
FORCEPROP 1 LAST HDL_TAP TRUE
J 0
(970 3970);
DISPLAY 2.276596 (970 3970);
PAINT GREEN (970 3970);
DISPLAY INVISIBLE (970 3970);
FORCEADD CAP..1
R 2
(450 4350);
FORCEPROP 1 LASTPIN (450 4450) $PN 1
J 2
(440 4430);
DISPLAY 0.617021 (440 4430);
PAINT ORANGE (440 4430);
FORCEPROP 1 LASTPIN (450 4250) $PN 2
J 2
(440 4230);
DISPLAY 0.617021 (440 4230);
PAINT ORANGE (440 4230);
FORCEPROP 1 LAST MATERIAL X7R
J 2
(400 4250);
DISPLAY 0.617021 (400 4250);
PAINT SKYBLUE (400 4250);
FORCEPROP 1 LAST VOLTAGE 16V
J 2
(400 4350);
DISPLAY 0.617021 (400 4350);
PAINT SKYBLUE (400 4350);
FORCEPROP 1 LAST PACK_TYPE 0402
J 2
(400 4150);
DISPLAY 0.617021 (400 4150);
PAINT SKYBLUE (400 4150);
FORCEPROP 1 LAST TOLERANCE 10%
J 2
(400 4300);
DISPLAY 0.617021 (400 4300);
PAINT SKYBLUE (400 4300);
FORCEPROP 1 LAST VALUE 0.22UF
J 2
(400 4400);
DISPLAY 0.617021 (400 4400);
PAINT SKYBLUE (400 4400);
FORCEPROP 1 LAST PART_NUMBER A36096-155
J 2
(400 4200);
DISPLAY 0.617021 (400 4200);
PAINT BLUE (400 4200);
FORCEPROP 1 LAST LOCATION C7G17
J 2
(400 4450);
DISPLAY 0.617021 (400 4450);
PAINT AQUA (400 4450);
FORCEPROP 2 LAST ROOM OCP_STEERING
J 2
(450 4350);
PAINT MONO (450 4350);
DISPLAY INVISIBLE (450 4350);
FORCEPROP 1 LAST PATH I44
J 2
(400 4500);
DISPLAY 0.978723 (400 4500);
PAINT WHITE (400 4500);
DISPLAY INVISIBLE (400 4500);
FORCEPROP 2 LAST CDS_LOCATION C7G17
J 2
(400 4450);
DISPLAY 0.617021 (400 4450);
PAINT AQUA (400 4450);
DISPLAY INVISIBLE (400 4450);
FORCEPROP 2 LAST SEC 1
J 0
(400 4550);
DISPLAY 0.680851 (400 4550);
PAINT MONO (400 4550);
DISPLAY INVISIBLE (400 4550);
FORCEPROP 2 LAST CDS_LIB mstr_discrete
J 0
(450 4350);
PAINT ORANGE (450 4350);
DISPLAY INVISIBLE (450 4350);
FORCEPROP 2 LAST SEC_TYPE 0402
J 0
(400 4550);
DISPLAY 1.021277 (400 4550);
PAINT ORANGE (400 4550);
DISPLAY INVISIBLE (400 4550);
FORCEADD CAP..1
R 2
(250 4650);
FORCEPROP 1 LASTPIN (250 4750) $PN 1
J 2
(240 4730);
DISPLAY 0.617021 (240 4730);
PAINT ORANGE (240 4730);
FORCEPROP 1 LASTPIN (250 4550) $PN 2
J 2
(240 4530);
DISPLAY 0.617021 (240 4530);
PAINT ORANGE (240 4530);
FORCEPROP 1 LAST MATERIAL X7R
J 2
(200 4550);
DISPLAY 0.617021 (200 4550);
PAINT SKYBLUE (200 4550);
FORCEPROP 1 LAST PACK_TYPE 0402
J 2
(200 4450);
DISPLAY 0.617021 (200 4450);
PAINT SKYBLUE (200 4450);
FORCEPROP 1 LAST TOLERANCE 10%
J 2
(200 4600);
DISPLAY 0.617021 (200 4600);
PAINT SKYBLUE (200 4600);
FORCEPROP 1 LAST PART_NUMBER A36096-155
J 2
(200 4500);
DISPLAY 0.617021 (200 4500);
PAINT BLUE (200 4500);
FORCEPROP 1 LAST LOCATION C7G15
J 2
(200 4750);
DISPLAY 0.617021 (200 4750);
PAINT AQUA (200 4750);
FORCEPROP 1 LAST VALUE 0.22UF
J 2
(200 4700);
DISPLAY 0.617021 (200 4700);
PAINT SKYBLUE (200 4700);
FORCEPROP 1 LAST VOLTAGE 16V
J 2
(200 4650);
DISPLAY 0.617021 (200 4650);
PAINT SKYBLUE (200 4650);
FORCEPROP 2 LAST ROOM OCP_STEERING
J 2
(250 4650);
PAINT MONO (250 4650);
DISPLAY INVISIBLE (250 4650);
FORCEPROP 1 LAST PATH I45
J 2
(200 4800);
DISPLAY 0.978723 (200 4800);
PAINT WHITE (200 4800);
DISPLAY INVISIBLE (200 4800);
FORCEPROP 2 LAST CDS_LOCATION C7G15
J 2
(200 4750);
DISPLAY 0.617021 (200 4750);
PAINT AQUA (200 4750);
DISPLAY INVISIBLE (200 4750);
FORCEPROP 2 LAST SEC 1
J 0
(200 4850);
DISPLAY 0.680851 (200 4850);
PAINT MONO (200 4850);
DISPLAY INVISIBLE (200 4850);
FORCEPROP 2 LAST CDS_LIB mstr_discrete
J 0
(250 4650);
PAINT ORANGE (250 4650);
DISPLAY INVISIBLE (250 4650);
FORCEPROP 2 LAST SEC_TYPE 0402
J 0
(200 4850);
DISPLAY 1.021277 (200 4850);
PAINT ORANGE (200 4850);
DISPLAY INVISIBLE (200 4850);
FORCEADD TAP..3
(925 3900);
FORCEPROP 3 LASTPIN (925 3850) SIG_NAME P3E_CPU0_PE2_SS_TXN<7>
J 0
(935 3860);
DISPLAY 0.659574 (935 3860);
PAINT MONO (935 3860);
DISPLAY INVISIBLE (935 3860);
FORCEPROP 1 LASTPIN (925 3850) BN 7
R 1
J 0
(918 3838);
DISPLAY 0.617021 (918 3838);
PAINT GREEN (918 3838);
FORCEPROP 1 LAST PATH I47
J 0
(923 3900);
DISPLAY 0.872340 (923 3900);
PAINT GREEN (923 3900);
DISPLAY INVISIBLE (923 3900);
FORCEPROP 2 LAST CDS_LIB mstr_standard
J 0
(925 3900);
PAINT ORANGE (925 3900);
DISPLAY INVISIBLE (925 3900);
FORCEPROP 1 LAST BODY_TYPE PLUMBING
J 0
(975 3850);
DISPLAY 2.276596 (975 3850);
PAINT GREEN (975 3850);
DISPLAY INVISIBLE (975 3850);
FORCEPROP 1 LAST HDL_TAP TRUE
J 0
(1245 3770);
DISPLAY 2.276596 (1245 3770);
PAINT GREEN (1245 3770);
DISPLAY INVISIBLE (1245 3770);
FORCEADD TAP..7
(875 4100);
FORCEPROP 3 LASTPIN (875 4150) SIG_NAME P3E_CPU0_PE2_SS_C_TXP<7>
J 0
(885 4160);
DISPLAY 0.659574 (885 4160);
PAINT MONO (885 4160);
DISPLAY INVISIBLE (885 4160);
FORCEPROP 1 LASTPIN (875 4150) BN 7
R 1
J 0
(868 4098);
DISPLAY 0.617021 (868 4098);
PAINT GREEN (868 4098);
FORCEPROP 1 LAST PATH I48
J 0
(873 4100);
DISPLAY 0.872340 (873 4100);
PAINT GREEN (873 4100);
DISPLAY INVISIBLE (873 4100);
FORCEPROP 2 LAST CDS_LIB mstr_standard
J 0
(875 4100);
PAINT ORANGE (875 4100);
DISPLAY INVISIBLE (875 4100);
FORCEPROP 1 LAST BODY_TYPE PLUMBING
J 0
(925 4100);
DISPLAY 2.276596 (925 4100);
PAINT GREEN (925 4100);
DISPLAY INVISIBLE (925 4100);
FORCEPROP 1 LAST HDL_TAP TRUE
J 0
(1195 3970);
DISPLAY 2.276596 (1195 3970);
PAINT GREEN (1195 3970);
DISPLAY INVISIBLE (1195 3970);
FORCEADD TAP..7
(1075 4100);
FORCEPROP 3 LASTPIN (1075 4150) SIG_NAME P3E_CPU0_PE2_SS_C_TXP<6>
J 0
(1085 4160);
DISPLAY 0.659574 (1085 4160);
PAINT MONO (1085 4160);
DISPLAY INVISIBLE (1085 4160);
FORCEPROP 1 LASTPIN (1075 4150) BN 6
R 1
J 0
(1068 4098);
DISPLAY 0.617021 (1068 4098);
PAINT GREEN (1068 4098);
FORCEPROP 1 LAST PATH I49
J 0
(1073 4100);
DISPLAY 0.872340 (1073 4100);
PAINT GREEN (1073 4100);
DISPLAY INVISIBLE (1073 4100);
FORCEPROP 2 LAST CDS_LIB mstr_standard
J 0
(1075 4100);
PAINT ORANGE (1075 4100);
DISPLAY INVISIBLE (1075 4100);
FORCEPROP 1 LAST BODY_TYPE PLUMBING
J 0
(1125 4100);
DISPLAY 2.276596 (1125 4100);
PAINT GREEN (1125 4100);
DISPLAY INVISIBLE (1125 4100);
FORCEPROP 1 LAST HDL_TAP TRUE
J 0
(1395 3970);
DISPLAY 2.276596 (1395 3970);
PAINT GREEN (1395 3970);
DISPLAY INVISIBLE (1395 3970);
FORCEADD TAP..7
(-500 3100);
FORCEPROP 3 LASTPIN (-500 3150) SIG_NAME P3E_CPU0_PE2_SS_C_TXN<14>
J 0
(-490 3160);
DISPLAY 0.659574 (-490 3160);
PAINT MONO (-490 3160);
DISPLAY INVISIBLE (-490 3160);
FORCEPROP 1 LASTPIN (-500 3150) BN 14
R 1
J 0
(-507 3098);
DISPLAY 0.617021 (-507 3098);
PAINT GREEN (-507 3098);
FORCEPROP 1 LAST PATH I5
J 0
(-502 3100);
DISPLAY 0.872340 (-502 3100);
PAINT GREEN (-502 3100);
DISPLAY INVISIBLE (-502 3100);
FORCEPROP 2 LAST CDS_LIB mstr_standard
J 0
(-500 3100);
PAINT ORANGE (-500 3100);
DISPLAY INVISIBLE (-500 3100);
FORCEPROP 1 LAST BODY_TYPE PLUMBING
J 0
(-450 3100);
DISPLAY 2.276596 (-450 3100);
PAINT GREEN (-450 3100);
DISPLAY INVISIBLE (-450 3100);
FORCEPROP 1 LAST HDL_TAP TRUE
J 0
(-180 2970);
DISPLAY 2.276596 (-180 2970);
PAINT GREEN (-180 2970);
DISPLAY INVISIBLE (-180 2970);
FORCEADD TAP..3
(1125 3900);
FORCEPROP 3 LASTPIN (1125 3850) SIG_NAME P3E_CPU0_PE2_SS_TXN<6>
J 0
(1135 3860);
DISPLAY 0.659574 (1135 3860);
PAINT MONO (1135 3860);
DISPLAY INVISIBLE (1135 3860);
FORCEPROP 1 LASTPIN (1125 3850) BN 6
R 1
J 0
(1118 3838);
DISPLAY 0.617021 (1118 3838);
PAINT GREEN (1118 3838);
FORCEPROP 1 LAST PATH I50
J 0
(1123 3900);
DISPLAY 0.872340 (1123 3900);
PAINT GREEN (1123 3900);
DISPLAY INVISIBLE (1123 3900);
FORCEPROP 2 LAST CDS_LIB mstr_standard
J 0
(1125 3900);
PAINT ORANGE (1125 3900);
DISPLAY INVISIBLE (1125 3900);
FORCEPROP 1 LAST BODY_TYPE PLUMBING
J 0
(1175 3850);
DISPLAY 2.276596 (1175 3850);
PAINT GREEN (1175 3850);
DISPLAY INVISIBLE (1175 3850);
FORCEPROP 1 LAST HDL_TAP TRUE
J 0
(1445 3770);
DISPLAY 2.276596 (1445 3770);
PAINT GREEN (1445 3770);
DISPLAY INVISIBLE (1445 3770);
FORCEADD CAP..1
R 2
(875 4350);
FORCEPROP 1 LASTPIN (875 4450) $PN 1
J 2
(865 4430);
DISPLAY 0.617021 (865 4430);
PAINT ORANGE (865 4430);
FORCEPROP 1 LASTPIN (875 4250) $PN 2
J 2
(865 4230);
DISPLAY 0.617021 (865 4230);
PAINT ORANGE (865 4230);
FORCEPROP 1 LAST PACK_TYPE 0402
J 2
(825 4150);
DISPLAY 0.617021 (825 4150);
PAINT SKYBLUE (825 4150);
FORCEPROP 1 LAST PART_NUMBER A36096-155
J 2
(825 4200);
DISPLAY 0.617021 (825 4200);
PAINT BLUE (825 4200);
FORCEPROP 1 LAST MATERIAL X7R
J 2
(825 4250);
DISPLAY 0.617021 (825 4250);
PAINT SKYBLUE (825 4250);
FORCEPROP 1 LAST TOLERANCE 10%
J 2
(825 4300);
DISPLAY 0.617021 (825 4300);
PAINT SKYBLUE (825 4300);
FORCEPROP 1 LAST VOLTAGE 16V
J 2
(825 4350);
DISPLAY 0.617021 (825 4350);
PAINT SKYBLUE (825 4350);
FORCEPROP 1 LAST VALUE 0.22UF
J 2
(825 4400);
DISPLAY 0.617021 (825 4400);
PAINT SKYBLUE (825 4400);
FORCEPROP 1 LAST LOCATION C7G21
J 2
(825 4450);
DISPLAY 0.617021 (825 4450);
PAINT AQUA (825 4450);
FORCEPROP 2 LAST ROOM OCP_STEERING
J 2
(875 4350);
PAINT MONO (875 4350);
DISPLAY INVISIBLE (875 4350);
FORCEPROP 1 LAST PATH I51
J 2
(825 4500);
DISPLAY 0.978723 (825 4500);
PAINT WHITE (825 4500);
DISPLAY INVISIBLE (825 4500);
FORCEPROP 2 LAST CDS_LOCATION C7G21
J 2
(825 4450);
DISPLAY 0.617021 (825 4450);
PAINT AQUA (825 4450);
DISPLAY INVISIBLE (825 4450);
FORCEPROP 2 LAST SEC 1
J 0
(825 4550);
DISPLAY 0.680851 (825 4550);
PAINT MONO (825 4550);
DISPLAY INVISIBLE (825 4550);
FORCEPROP 2 LAST SEC_TYPE 0402
J 0
(825 4550);
DISPLAY 1.021277 (825 4550);
PAINT ORANGE (825 4550);
DISPLAY INVISIBLE (825 4550);
FORCEPROP 2 LAST CDS_LIB mstr_discrete
J 0
(875 4350);
PAINT ORANGE (875 4350);
DISPLAY INVISIBLE (875 4350);
FORCEADD CAP..1
R 2
(1075 4650);
FORCEPROP 1 LASTPIN (1075 4750) $PN 1
J 2
(1065 4730);
DISPLAY 0.617021 (1065 4730);
PAINT ORANGE (1065 4730);
FORCEPROP 1 LASTPIN (1075 4550) $PN 2
J 2
(1065 4530);
DISPLAY 0.617021 (1065 4530);
PAINT ORANGE (1065 4530);
FORCEPROP 1 LAST PACK_TYPE 0402
J 2
(1025 4450);
DISPLAY 0.617021 (1025 4450);
PAINT SKYBLUE (1025 4450);
FORCEPROP 1 LAST TOLERANCE 10%
J 2
(1025 4600);
DISPLAY 0.617021 (1025 4600);
PAINT SKYBLUE (1025 4600);
FORCEPROP 1 LAST MATERIAL X7R
J 2
(1025 4550);
DISPLAY 0.617021 (1025 4550);
PAINT SKYBLUE (1025 4550);
FORCEPROP 1 LAST VOLTAGE 16V
J 2
(1025 4650);
DISPLAY 0.617021 (1025 4650);
PAINT SKYBLUE (1025 4650);
FORCEPROP 1 LAST LOCATION C7G23
J 2
(1025 4750);
DISPLAY 0.617021 (1025 4750);
PAINT AQUA (1025 4750);
FORCEPROP 1 LAST PART_NUMBER A36096-155
J 2
(1025 4500);
DISPLAY 0.617021 (1025 4500);
PAINT BLUE (1025 4500);
FORCEPROP 1 LAST VALUE 0.22UF
J 2
(1025 4700);
DISPLAY 0.617021 (1025 4700);
PAINT SKYBLUE (1025 4700);
FORCEPROP 2 LAST ROOM OCP_STEERING
J 2
(1075 4650);
PAINT MONO (1075 4650);
DISPLAY INVISIBLE (1075 4650);
FORCEPROP 1 LAST PATH I52
J 2
(1025 4800);
DISPLAY 0.978723 (1025 4800);
PAINT WHITE (1025 4800);
DISPLAY INVISIBLE (1025 4800);
FORCEPROP 2 LAST CDS_LOCATION C7G23
J 2
(1025 4750);
DISPLAY 0.617021 (1025 4750);
PAINT AQUA (1025 4750);
DISPLAY INVISIBLE (1025 4750);
FORCEPROP 2 LAST SEC 1
J 0
(1025 4850);
DISPLAY 0.680851 (1025 4850);
PAINT MONO (1025 4850);
DISPLAY INVISIBLE (1025 4850);
FORCEPROP 2 LAST SEC_TYPE 0402
J 0
(1025 4850);
DISPLAY 1.021277 (1025 4850);
PAINT ORANGE (1025 4850);
DISPLAY INVISIBLE (1025 4850);
FORCEPROP 2 LAST CDS_LIB mstr_discrete
J 0
(1075 4650);
PAINT ORANGE (1075 4650);
DISPLAY INVISIBLE (1075 4650);
FORCEADD TAP..7
(1525 3100);
FORCEPROP 3 LASTPIN (1525 3150) SIG_NAME P3E_CPU0_PE2_SS_C_TXN<4>
J 0
(1535 3160);
DISPLAY 0.659574 (1535 3160);
PAINT MONO (1535 3160);
DISPLAY INVISIBLE (1535 3160);
FORCEPROP 1 LASTPIN (1525 3150) BN 4
R 1
J 0
(1518 3098);
DISPLAY 0.617021 (1518 3098);
PAINT GREEN (1518 3098);
FORCEPROP 1 LAST PATH I53
J 0
(1523 3100);
DISPLAY 0.872340 (1523 3100);
PAINT GREEN (1523 3100);
DISPLAY INVISIBLE (1523 3100);
FORCEPROP 2 LAST CDS_LIB mstr_standard
J 0
(1525 3100);
PAINT ORANGE (1525 3100);
DISPLAY INVISIBLE (1525 3100);
FORCEPROP 1 LAST BODY_TYPE PLUMBING
J 0
(1575 3100);
DISPLAY 2.276596 (1575 3100);
PAINT GREEN (1575 3100);
DISPLAY INVISIBLE (1575 3100);
FORCEPROP 1 LAST HDL_TAP TRUE
J 0
(1845 2970);
DISPLAY 2.276596 (1845 2970);
PAINT GREEN (1845 2970);
DISPLAY INVISIBLE (1845 2970);
FORCEADD TAP..7
(1325 3100);
FORCEPROP 3 LASTPIN (1325 3150) SIG_NAME P3E_CPU0_PE2_SS_C_TXN<5>
J 0
(1335 3160);
DISPLAY 0.659574 (1335 3160);
PAINT MONO (1335 3160);
DISPLAY INVISIBLE (1335 3160);
FORCEPROP 1 LASTPIN (1325 3150) BN 5
R 1
J 0
(1318 3098);
DISPLAY 0.617021 (1318 3098);
PAINT GREEN (1318 3098);
FORCEPROP 1 LAST PATH I54
J 0
(1323 3100);
DISPLAY 0.872340 (1323 3100);
PAINT GREEN (1323 3100);
DISPLAY INVISIBLE (1323 3100);
FORCEPROP 2 LAST CDS_LIB mstr_standard
J 0
(1325 3100);
PAINT ORANGE (1325 3100);
DISPLAY INVISIBLE (1325 3100);
FORCEPROP 1 LAST BODY_TYPE PLUMBING
J 0
(1375 3100);
DISPLAY 2.276596 (1375 3100);
PAINT GREEN (1375 3100);
DISPLAY INVISIBLE (1375 3100);
FORCEPROP 1 LAST HDL_TAP TRUE
J 0
(1645 2970);
DISPLAY 2.276596 (1645 2970);
PAINT GREEN (1645 2970);
DISPLAY INVISIBLE (1645 2970);
FORCEADD CAP..1
R 2
(1325 3350);
FORCEPROP 1 LASTPIN (1325 3450) $PN 1
J 2
(1315 3430);
DISPLAY 0.617021 (1315 3430);
PAINT ORANGE (1315 3430);
FORCEPROP 1 LASTPIN (1325 3250) $PN 2
J 2
(1315 3230);
DISPLAY 0.617021 (1315 3230);
PAINT ORANGE (1315 3230);
FORCEPROP 1 LAST MATERIAL X7R
J 2
(1275 3250);
DISPLAY 0.617021 (1275 3250);
PAINT SKYBLUE (1275 3250);
FORCEPROP 1 LAST VOLTAGE 16V
J 2
(1275 3350);
DISPLAY 0.617021 (1275 3350);
PAINT SKYBLUE (1275 3350);
FORCEPROP 1 LAST PACK_TYPE 0402
J 2
(1275 3150);
DISPLAY 0.617021 (1275 3150);
PAINT SKYBLUE (1275 3150);
FORCEPROP 1 LAST TOLERANCE 10%
J 2
(1275 3300);
DISPLAY 0.617021 (1275 3300);
PAINT SKYBLUE (1275 3300);
FORCEPROP 1 LAST VALUE 0.22UF
J 2
(1275 3400);
DISPLAY 0.617021 (1275 3400);
PAINT SKYBLUE (1275 3400);
FORCEPROP 1 LAST LOCATION C7G26
J 2
(1275 3450);
DISPLAY 0.617021 (1275 3450);
PAINT AQUA (1275 3450);
FORCEPROP 1 LAST PART_NUMBER A36096-155
J 2
(1275 3200);
DISPLAY 0.617021 (1275 3200);
PAINT BLUE (1275 3200);
FORCEPROP 2 LAST ROOM OCP_STEERING
J 2
(1325 3350);
PAINT MONO (1325 3350);
DISPLAY INVISIBLE (1325 3350);
FORCEPROP 1 LAST PATH I55
J 2
(1275 3500);
DISPLAY 0.978723 (1275 3500);
PAINT WHITE (1275 3500);
DISPLAY INVISIBLE (1275 3500);
FORCEPROP 2 LAST CDS_LOCATION C7G26
J 2
(1275 3450);
DISPLAY 0.617021 (1275 3450);
PAINT AQUA (1275 3450);
DISPLAY INVISIBLE (1275 3450);
FORCEPROP 2 LAST SEC 1
J 0
(1275 3550);
DISPLAY 0.680851 (1275 3550);
PAINT MONO (1275 3550);
DISPLAY INVISIBLE (1275 3550);
FORCEPROP 2 LAST SEC_TYPE 0402
J 0
(1275 3550);
DISPLAY 1.021277 (1275 3550);
PAINT ORANGE (1275 3550);
DISPLAY INVISIBLE (1275 3550);
FORCEPROP 2 LAST CDS_LIB mstr_discrete
J 0
(1325 3350);
PAINT ORANGE (1325 3350);
DISPLAY INVISIBLE (1325 3350);
FORCEADD CAP..1
R 2
(1725 3350);
FORCEPROP 1 LASTPIN (1725 3450) $PN 1
J 2
(1715 3430);
DISPLAY 0.617021 (1715 3430);
PAINT ORANGE (1715 3430);
FORCEPROP 1 LASTPIN (1725 3250) $PN 2
J 2
(1715 3230);
DISPLAY 0.617021 (1715 3230);
PAINT ORANGE (1715 3230);
FORCEPROP 1 LAST MATERIAL X7R
J 2
(1675 3250);
DISPLAY 0.617021 (1675 3250);
PAINT SKYBLUE (1675 3250);
FORCEPROP 1 LAST VOLTAGE 16V
J 2
(1675 3350);
DISPLAY 0.617021 (1675 3350);
PAINT SKYBLUE (1675 3350);
FORCEPROP 1 LAST PACK_TYPE 0402
J 2
(1675 3150);
DISPLAY 0.617021 (1675 3150);
PAINT SKYBLUE (1675 3150);
FORCEPROP 1 LAST VALUE 0.22UF
J 2
(1675 3400);
DISPLAY 0.617021 (1675 3400);
PAINT SKYBLUE (1675 3400);
FORCEPROP 1 LAST LOCATION C8G4
J 2
(1675 3450);
DISPLAY 0.617021 (1675 3450);
PAINT AQUA (1675 3450);
FORCEPROP 1 LAST TOLERANCE 10%
J 2
(1675 3300);
DISPLAY 0.617021 (1675 3300);
PAINT SKYBLUE (1675 3300);
FORCEPROP 1 LAST PART_NUMBER A36096-155
J 2
(1675 3200);
DISPLAY 0.617021 (1675 3200);
PAINT BLUE (1675 3200);
FORCEPROP 2 LAST ROOM OCP_STEERING
J 2
(1725 3350);
PAINT MONO (1725 3350);
DISPLAY INVISIBLE (1725 3350);
FORCEPROP 1 LAST PATH I56
J 2
(1675 3500);
DISPLAY 0.978723 (1675 3500);
PAINT WHITE (1675 3500);
DISPLAY INVISIBLE (1675 3500);
FORCEPROP 2 LAST CDS_LOCATION C8G4
J 2
(1675 3450);
DISPLAY 0.617021 (1675 3450);
PAINT AQUA (1675 3450);
DISPLAY INVISIBLE (1675 3450);
FORCEPROP 2 LAST SEC 1
J 0
(1675 3550);
DISPLAY 0.680851 (1675 3550);
PAINT MONO (1675 3550);
DISPLAY INVISIBLE (1675 3550);
FORCEPROP 2 LAST SEC_TYPE 0402
J 0
(1675 3550);
DISPLAY 1.021277 (1675 3550);
PAINT ORANGE (1675 3550);
DISPLAY INVISIBLE (1675 3550);
FORCEPROP 2 LAST CDS_LIB mstr_discrete
J 0
(1725 3350);
PAINT ORANGE (1725 3350);
DISPLAY INVISIBLE (1725 3350);
FORCEADD TAP..7
(1725 3100);
FORCEPROP 3 LASTPIN (1725 3150) SIG_NAME P3E_CPU0_PE2_SS_C_TXN<3>
J 0
(1735 3160);
DISPLAY 0.659574 (1735 3160);
PAINT MONO (1735 3160);
DISPLAY INVISIBLE (1735 3160);
FORCEPROP 1 LASTPIN (1725 3150) BN 3
R 1
J 0
(1718 3098);
DISPLAY 0.617021 (1718 3098);
PAINT GREEN (1718 3098);
FORCEPROP 1 LAST PATH I57
J 0
(1723 3100);
DISPLAY 0.872340 (1723 3100);
PAINT GREEN (1723 3100);
DISPLAY INVISIBLE (1723 3100);
FORCEPROP 2 LAST CDS_LIB mstr_standard
J 0
(1725 3100);
PAINT ORANGE (1725 3100);
DISPLAY INVISIBLE (1725 3100);
FORCEPROP 1 LAST BODY_TYPE PLUMBING
J 0
(1775 3100);
DISPLAY 2.276596 (1775 3100);
PAINT GREEN (1775 3100);
DISPLAY INVISIBLE (1775 3100);
FORCEPROP 1 LAST HDL_TAP TRUE
J 0
(2045 2970);
DISPLAY 2.276596 (2045 2970);
PAINT GREEN (2045 2970);
DISPLAY INVISIBLE (2045 2970);
FORCEADD CAP..1
R 2
(1525 3650);
FORCEPROP 1 LASTPIN (1525 3750) $PN 1
J 2
(1515 3730);
DISPLAY 0.617021 (1515 3730);
PAINT ORANGE (1515 3730);
FORCEPROP 1 LASTPIN (1525 3550) $PN 2
J 2
(1515 3530);
DISPLAY 0.617021 (1515 3530);
PAINT ORANGE (1515 3530);
FORCEPROP 1 LAST MATERIAL X7R
J 2
(1475 3550);
DISPLAY 0.617021 (1475 3550);
PAINT SKYBLUE (1475 3550);
FORCEPROP 1 LAST VOLTAGE 16V
J 2
(1475 3650);
DISPLAY 0.617021 (1475 3650);
PAINT SKYBLUE (1475 3650);
FORCEPROP 1 LAST PART_NUMBER A36096-155
J 2
(1475 3500);
DISPLAY 0.617021 (1475 3500);
PAINT BLUE (1475 3500);
FORCEPROP 1 LAST LOCATION C8G2
J 2
(1475 3750);
DISPLAY 0.617021 (1475 3750);
PAINT AQUA (1475 3750);
FORCEPROP 1 LAST TOLERANCE 10%
J 2
(1475 3600);
DISPLAY 0.617021 (1475 3600);
PAINT SKYBLUE (1475 3600);
FORCEPROP 1 LAST VALUE 0.22UF
J 2
(1475 3700);
DISPLAY 0.617021 (1475 3700);
PAINT SKYBLUE (1475 3700);
FORCEPROP 1 LAST PACK_TYPE 0402
J 2
(1475 3450);
DISPLAY 0.617021 (1475 3450);
PAINT SKYBLUE (1475 3450);
FORCEPROP 2 LAST ROOM OCP_STEERING
J 2
(1525 3650);
PAINT MONO (1525 3650);
DISPLAY INVISIBLE (1525 3650);
FORCEPROP 1 LAST PATH I58
J 2
(1475 3800);
DISPLAY 0.978723 (1475 3800);
PAINT WHITE (1475 3800);
DISPLAY INVISIBLE (1475 3800);
FORCEPROP 2 LAST CDS_LOCATION C8G2
J 2
(1475 3750);
DISPLAY 0.617021 (1475 3750);
PAINT AQUA (1475 3750);
DISPLAY INVISIBLE (1475 3750);
FORCEPROP 2 LAST SEC 1
J 0
(1475 3850);
DISPLAY 0.680851 (1475 3850);
PAINT MONO (1475 3850);
DISPLAY INVISIBLE (1475 3850);
FORCEPROP 2 LAST SEC_TYPE 0402
J 0
(1475 3850);
DISPLAY 1.021277 (1475 3850);
PAINT ORANGE (1475 3850);
DISPLAY INVISIBLE (1475 3850);
FORCEPROP 2 LAST CDS_LIB mstr_discrete
J 0
(1525 3650);
PAINT ORANGE (1525 3650);
DISPLAY INVISIBLE (1525 3650);
FORCEADD TAP..7
(2125 3100);
FORCEPROP 3 LASTPIN (2125 3150) SIG_NAME P3E_CPU0_PE2_SS_C_TXN<1>
J 0
(2135 3160);
DISPLAY 0.659574 (2135 3160);
PAINT MONO (2135 3160);
DISPLAY INVISIBLE (2135 3160);
FORCEPROP 1 LASTPIN (2125 3150) BN 1
R 1
J 0
(2118 3098);
DISPLAY 0.617021 (2118 3098);
PAINT GREEN (2118 3098);
FORCEPROP 1 LAST PATH I59
J 0
(2123 3100);
DISPLAY 0.872340 (2123 3100);
PAINT GREEN (2123 3100);
DISPLAY INVISIBLE (2123 3100);
FORCEPROP 2 LAST CDS_LIB mstr_standard
J 0
(2125 3100);
PAINT ORANGE (2125 3100);
DISPLAY INVISIBLE (2125 3100);
FORCEPROP 1 LAST BODY_TYPE PLUMBING
J 0
(2175 3100);
DISPLAY 2.276596 (2175 3100);
PAINT GREEN (2175 3100);
DISPLAY INVISIBLE (2175 3100);
FORCEPROP 1 LAST HDL_TAP TRUE
J 0
(2445 2970);
DISPLAY 2.276596 (2445 2970);
PAINT GREEN (2445 2970);
DISPLAY INVISIBLE (2445 2970);
FORCEADD CAP..1
R 2
(-700 3350);
FORCEPROP 1 LAST MATERIAL X7R
J 2
(-750 3250);
DISPLAY 0.617021 (-750 3250);
PAINT SKYBLUE (-750 3250);
FORCEPROP 1 LAST VOLTAGE 16V
J 2
(-750 3350);
DISPLAY 0.617021 (-750 3350);
PAINT SKYBLUE (-750 3350);
FORCEPROP 1 LAST TOLERANCE 10%
J 2
(-750 3300);
DISPLAY 0.617021 (-750 3300);
PAINT SKYBLUE (-750 3300);
FORCEPROP 1 LAST VALUE 0.22UF
J 2
(-750 3400);
DISPLAY 0.617021 (-750 3400);
PAINT SKYBLUE (-750 3400);
FORCEPROP 1 LAST PART_NUMBER A36096-155
J 2
(-750 3200);
DISPLAY 0.617021 (-750 3200);
PAINT BLUE (-750 3200);
FORCEPROP 1 LAST LOCATION C7G6
J 2
(-750 3450);
DISPLAY 0.617021 (-750 3450);
PAINT AQUA (-750 3450);
FORCEPROP 1 LAST PACK_TYPE 0402
J 2
(-750 3150);
DISPLAY 0.617021 (-750 3150);
PAINT SKYBLUE (-750 3150);
FORCEPROP 1 LASTPIN (-700 3450) $PN 1
J 2
(-710 3430);
DISPLAY 0.787234 (-710 3430);
PAINT ORANGE (-710 3430);
DISPLAY INVISIBLE (-710 3430);
FORCEPROP 1 LASTPIN (-700 3250) $PN 2
J 2
(-710 3230);
DISPLAY 0.787234 (-710 3230);
PAINT ORANGE (-710 3230);
DISPLAY INVISIBLE (-710 3230);
FORCEPROP 2 LAST ROOM OCP_STEERING
J 2
(-700 3350);
PAINT MONO (-700 3350);
DISPLAY INVISIBLE (-700 3350);
FORCEPROP 1 LAST PATH I6
J 2
(-750 3500);
DISPLAY 0.978723 (-750 3500);
PAINT WHITE (-750 3500);
DISPLAY INVISIBLE (-750 3500);
FORCEPROP 2 LAST CDS_LOCATION C7G6
J 2
(-750 3450);
DISPLAY 0.617021 (-750 3450);
PAINT AQUA (-750 3450);
DISPLAY INVISIBLE (-750 3450);
FORCEPROP 2 LAST $SEC 1
J 0
(-750 3550);
DISPLAY 0.680851 (-750 3550);
PAINT MONO (-750 3550);
DISPLAY INVISIBLE (-750 3550);
FORCEPROP 2 LAST CDS_SEC 1
J 0
(-750 3550);
DISPLAY 1.021277 (-750 3550);
PAINT ORANGE (-750 3550);
DISPLAY INVISIBLE (-750 3550);
FORCEPROP 2 LAST CDS_LIB mstr_discrete
J 0
(-700 3350);
PAINT ORANGE (-700 3350);
DISPLAY INVISIBLE (-700 3350);
FORCEADD TAP..7
(1925 3100);
FORCEPROP 3 LASTPIN (1925 3150) SIG_NAME P3E_CPU0_PE2_SS_C_TXN<2>
J 0
(1935 3160);
DISPLAY 0.659574 (1935 3160);
PAINT MONO (1935 3160);
DISPLAY INVISIBLE (1935 3160);
FORCEPROP 1 LASTPIN (1925 3150) BN 2
R 1
J 0
(1918 3098);
DISPLAY 0.617021 (1918 3098);
PAINT GREEN (1918 3098);
FORCEPROP 1 LAST PATH I60
J 0
(1923 3100);
DISPLAY 0.872340 (1923 3100);
PAINT GREEN (1923 3100);
DISPLAY INVISIBLE (1923 3100);
FORCEPROP 2 LAST CDS_LIB mstr_standard
J 0
(1925 3100);
PAINT ORANGE (1925 3100);
DISPLAY INVISIBLE (1925 3100);
FORCEPROP 1 LAST BODY_TYPE PLUMBING
J 0
(1975 3100);
DISPLAY 2.276596 (1975 3100);
PAINT GREEN (1975 3100);
DISPLAY INVISIBLE (1975 3100);
FORCEPROP 1 LAST HDL_TAP TRUE
J 0
(2245 2970);
DISPLAY 2.276596 (2245 2970);
PAINT GREEN (2245 2970);
DISPLAY INVISIBLE (2245 2970);
FORCEADD CAP..1
R 2
(1925 3650);
FORCEPROP 1 LASTPIN (1925 3750) $PN 1
J 2
(1915 3730);
DISPLAY 0.617021 (1915 3730);
PAINT ORANGE (1915 3730);
FORCEPROP 1 LASTPIN (1925 3550) $PN 2
J 2
(1915 3530);
DISPLAY 0.617021 (1915 3530);
PAINT ORANGE (1915 3530);
FORCEPROP 1 LAST PACK_TYPE 0402
J 2
(1875 3450);
DISPLAY 0.617021 (1875 3450);
PAINT SKYBLUE (1875 3450);
FORCEPROP 1 LAST TOLERANCE 10%
J 2
(1875 3600);
DISPLAY 0.617021 (1875 3600);
PAINT SKYBLUE (1875 3600);
FORCEPROP 1 LAST PART_NUMBER A36096-155
J 2
(1875 3500);
DISPLAY 0.617021 (1875 3500);
PAINT BLUE (1875 3500);
FORCEPROP 1 LAST LOCATION C8G6
J 2
(1875 3750);
DISPLAY 0.617021 (1875 3750);
PAINT AQUA (1875 3750);
FORCEPROP 1 LAST VOLTAGE 16V
J 2
(1875 3650);
DISPLAY 0.617021 (1875 3650);
PAINT SKYBLUE (1875 3650);
FORCEPROP 1 LAST VALUE 0.22UF
J 2
(1875 3700);
DISPLAY 0.617021 (1875 3700);
PAINT SKYBLUE (1875 3700);
FORCEPROP 1 LAST MATERIAL X7R
J 2
(1875 3550);
DISPLAY 0.617021 (1875 3550);
PAINT SKYBLUE (1875 3550);
FORCEPROP 2 LAST ROOM OCP_STEERING
J 2
(1925 3650);
PAINT MONO (1925 3650);
DISPLAY INVISIBLE (1925 3650);
FORCEPROP 1 LAST PATH I61
J 2
(1875 3800);
DISPLAY 0.978723 (1875 3800);
PAINT WHITE (1875 3800);
DISPLAY INVISIBLE (1875 3800);
FORCEPROP 2 LAST CDS_LOCATION C8G6
J 2
(1875 3750);
DISPLAY 0.617021 (1875 3750);
PAINT AQUA (1875 3750);
DISPLAY INVISIBLE (1875 3750);
FORCEPROP 2 LAST SEC 1
J 0
(1875 3850);
DISPLAY 0.680851 (1875 3850);
PAINT MONO (1875 3850);
DISPLAY INVISIBLE (1875 3850);
FORCEPROP 2 LAST SEC_TYPE 0402
J 0
(1875 3850);
DISPLAY 1.021277 (1875 3850);
PAINT ORANGE (1875 3850);
DISPLAY INVISIBLE (1875 3850);
FORCEPROP 2 LAST CDS_LIB mstr_discrete
J 0
(1925 3650);
PAINT ORANGE (1925 3650);
DISPLAY INVISIBLE (1925 3650);
FORCEADD CAP..1
R 2
(2125 3350);
FORCEPROP 1 LASTPIN (2125 3450) $PN 1
J 2
(2115 3430);
DISPLAY 0.617021 (2115 3430);
PAINT ORANGE (2115 3430);
FORCEPROP 1 LASTPIN (2125 3250) $PN 2
J 2
(2115 3230);
DISPLAY 0.617021 (2115 3230);
PAINT ORANGE (2115 3230);
FORCEPROP 1 LAST MATERIAL X7R
J 2
(2075 3250);
DISPLAY 0.617021 (2075 3250);
PAINT SKYBLUE (2075 3250);
FORCEPROP 1 LAST VOLTAGE 16V
J 2
(2075 3350);
DISPLAY 0.617021 (2075 3350);
PAINT SKYBLUE (2075 3350);
FORCEPROP 1 LAST PACK_TYPE 0402
J 2
(2075 3150);
DISPLAY 0.617021 (2075 3150);
PAINT SKYBLUE (2075 3150);
FORCEPROP 1 LAST TOLERANCE 10%
J 2
(2075 3300);
DISPLAY 0.617021 (2075 3300);
PAINT SKYBLUE (2075 3300);
FORCEPROP 1 LAST VALUE 0.22UF
J 2
(2075 3400);
DISPLAY 0.617021 (2075 3400);
PAINT SKYBLUE (2075 3400);
FORCEPROP 1 LAST LOCATION C8G7
J 2
(2075 3450);
DISPLAY 0.617021 (2075 3450);
PAINT AQUA (2075 3450);
FORCEPROP 1 LAST PART_NUMBER A36096-155
J 2
(2075 3200);
DISPLAY 0.617021 (2075 3200);
PAINT BLUE (2075 3200);
FORCEPROP 2 LAST ROOM OCP_STEERING
J 2
(2125 3350);
PAINT MONO (2125 3350);
DISPLAY INVISIBLE (2125 3350);
FORCEPROP 1 LAST PATH I62
J 2
(2075 3500);
DISPLAY 0.978723 (2075 3500);
PAINT WHITE (2075 3500);
DISPLAY INVISIBLE (2075 3500);
FORCEPROP 2 LAST CDS_LOCATION C8G7
J 2
(2075 3450);
DISPLAY 0.617021 (2075 3450);
PAINT AQUA (2075 3450);
DISPLAY INVISIBLE (2075 3450);
FORCEPROP 2 LAST SEC 1
J 0
(2075 3550);
DISPLAY 0.680851 (2075 3550);
PAINT MONO (2075 3550);
DISPLAY INVISIBLE (2075 3550);
FORCEPROP 2 LAST SEC_TYPE 0402
J 0
(2075 3550);
DISPLAY 1.021277 (2075 3550);
PAINT ORANGE (2075 3550);
DISPLAY INVISIBLE (2075 3550);
FORCEPROP 2 LAST CDS_LIB mstr_discrete
J 0
(2125 3350);
PAINT ORANGE (2125 3350);
DISPLAY INVISIBLE (2125 3350);
FORCEADD TAP..3
(1325 3900);
FORCEPROP 3 LASTPIN (1325 3850) SIG_NAME P3E_CPU0_PE2_SS_TXN<5>
J 0
(1335 3860);
DISPLAY 0.659574 (1335 3860);
PAINT MONO (1335 3860);
DISPLAY INVISIBLE (1335 3860);
FORCEPROP 1 LASTPIN (1325 3850) BN 5
R 1
J 0
(1318 3838);
DISPLAY 0.617021 (1318 3838);
PAINT GREEN (1318 3838);
FORCEPROP 1 LAST PATH I63
J 0
(1323 3900);
DISPLAY 0.872340 (1323 3900);
PAINT GREEN (1323 3900);
DISPLAY INVISIBLE (1323 3900);
FORCEPROP 2 LAST CDS_LIB mstr_standard
J 0
(1325 3900);
PAINT ORANGE (1325 3900);
DISPLAY INVISIBLE (1325 3900);
FORCEPROP 1 LAST BODY_TYPE PLUMBING
J 0
(1375 3850);
DISPLAY 2.276596 (1375 3850);
PAINT GREEN (1375 3850);
DISPLAY INVISIBLE (1375 3850);
FORCEPROP 1 LAST HDL_TAP TRUE
J 0
(1645 3770);
DISPLAY 2.276596 (1645 3770);
PAINT GREEN (1645 3770);
DISPLAY INVISIBLE (1645 3770);
FORCEADD TAP..7
(1275 4100);
FORCEPROP 3 LASTPIN (1275 4150) SIG_NAME P3E_CPU0_PE2_SS_C_TXP<5>
J 0
(1285 4160);
DISPLAY 0.659574 (1285 4160);
PAINT MONO (1285 4160);
DISPLAY INVISIBLE (1285 4160);
FORCEPROP 1 LASTPIN (1275 4150) BN 5
R 1
J 0
(1268 4098);
DISPLAY 0.617021 (1268 4098);
PAINT GREEN (1268 4098);
FORCEPROP 1 LAST PATH I64
J 0
(1273 4100);
DISPLAY 0.872340 (1273 4100);
PAINT GREEN (1273 4100);
DISPLAY INVISIBLE (1273 4100);
FORCEPROP 2 LAST CDS_LIB mstr_standard
J 0
(1275 4100);
PAINT ORANGE (1275 4100);
DISPLAY INVISIBLE (1275 4100);
FORCEPROP 1 LAST BODY_TYPE PLUMBING
J 0
(1325 4100);
DISPLAY 2.276596 (1325 4100);
PAINT GREEN (1325 4100);
DISPLAY INVISIBLE (1325 4100);
FORCEPROP 1 LAST HDL_TAP TRUE
J 0
(1595 3970);
DISPLAY 2.276596 (1595 3970);
PAINT GREEN (1595 3970);
DISPLAY INVISIBLE (1595 3970);
FORCEADD TAP..3
(1525 3900);
FORCEPROP 3 LASTPIN (1525 3850) SIG_NAME P3E_CPU0_PE2_SS_TXN<4>
J 0
(1535 3860);
DISPLAY 0.659574 (1535 3860);
PAINT MONO (1535 3860);
DISPLAY INVISIBLE (1535 3860);
FORCEPROP 1 LASTPIN (1525 3850) BN 4
R 1
J 0
(1518 3838);
DISPLAY 0.617021 (1518 3838);
PAINT GREEN (1518 3838);
FORCEPROP 1 LAST PATH I65
J 0
(1523 3900);
DISPLAY 0.872340 (1523 3900);
PAINT GREEN (1523 3900);
DISPLAY INVISIBLE (1523 3900);
FORCEPROP 2 LAST CDS_LIB mstr_standard
J 0
(1525 3900);
PAINT ORANGE (1525 3900);
DISPLAY INVISIBLE (1525 3900);
FORCEPROP 1 LAST BODY_TYPE PLUMBING
J 0
(1575 3850);
DISPLAY 2.276596 (1575 3850);
PAINT GREEN (1575 3850);
DISPLAY INVISIBLE (1575 3850);
FORCEPROP 1 LAST HDL_TAP TRUE
J 0
(1845 3770);
DISPLAY 2.276596 (1845 3770);
PAINT GREEN (1845 3770);
DISPLAY INVISIBLE (1845 3770);
FORCEADD TAP..7
(1475 4100);
FORCEPROP 3 LASTPIN (1475 4150) SIG_NAME P3E_CPU0_PE2_SS_C_TXP<4>
J 0
(1485 4160);
DISPLAY 0.659574 (1485 4160);
PAINT MONO (1485 4160);
DISPLAY INVISIBLE (1485 4160);
FORCEPROP 1 LASTPIN (1475 4150) BN 4
R 1
J 0
(1468 4098);
DISPLAY 0.617021 (1468 4098);
PAINT GREEN (1468 4098);
FORCEPROP 1 LAST PATH I66
J 0
(1473 4100);
DISPLAY 0.872340 (1473 4100);
PAINT GREEN (1473 4100);
DISPLAY INVISIBLE (1473 4100);
FORCEPROP 2 LAST CDS_LIB mstr_standard
J 0
(1475 4100);
PAINT ORANGE (1475 4100);
DISPLAY INVISIBLE (1475 4100);
FORCEPROP 1 LAST BODY_TYPE PLUMBING
J 0
(1525 4100);
DISPLAY 2.276596 (1525 4100);
PAINT GREEN (1525 4100);
DISPLAY INVISIBLE (1525 4100);
FORCEPROP 1 LAST HDL_TAP TRUE
J 0
(1795 3970);
DISPLAY 2.276596 (1795 3970);
PAINT GREEN (1795 3970);
DISPLAY INVISIBLE (1795 3970);
FORCEADD TAP..7
(1675 4100);
FORCEPROP 3 LASTPIN (1675 4150) SIG_NAME P3E_CPU0_PE2_SS_C_TXP<3>
J 0
(1685 4160);
DISPLAY 0.659574 (1685 4160);
PAINT MONO (1685 4160);
DISPLAY INVISIBLE (1685 4160);
FORCEPROP 1 LASTPIN (1675 4150) BN 3
R 1
J 0
(1668 4098);
DISPLAY 0.617021 (1668 4098);
PAINT GREEN (1668 4098);
FORCEPROP 1 LAST PATH I67
J 0
(1673 4100);
DISPLAY 0.872340 (1673 4100);
PAINT GREEN (1673 4100);
DISPLAY INVISIBLE (1673 4100);
FORCEPROP 2 LAST CDS_LIB mstr_standard
J 0
(1675 4100);
PAINT ORANGE (1675 4100);
DISPLAY INVISIBLE (1675 4100);
FORCEPROP 1 LAST BODY_TYPE PLUMBING
J 0
(1725 4100);
DISPLAY 2.276596 (1725 4100);
PAINT GREEN (1725 4100);
DISPLAY INVISIBLE (1725 4100);
FORCEPROP 1 LAST HDL_TAP TRUE
J 0
(1995 3970);
DISPLAY 2.276596 (1995 3970);
PAINT GREEN (1995 3970);
DISPLAY INVISIBLE (1995 3970);
FORCEADD TAP..3
(1725 3900);
FORCEPROP 3 LASTPIN (1725 3850) SIG_NAME P3E_CPU0_PE2_SS_TXN<3>
J 0
(1735 3860);
DISPLAY 0.659574 (1735 3860);
PAINT MONO (1735 3860);
DISPLAY INVISIBLE (1735 3860);
FORCEPROP 1 LASTPIN (1725 3850) BN 3
R 1
J 0
(1718 3838);
DISPLAY 0.617021 (1718 3838);
PAINT GREEN (1718 3838);
FORCEPROP 1 LAST PATH I68
J 0
(1723 3900);
DISPLAY 0.872340 (1723 3900);
PAINT GREEN (1723 3900);
DISPLAY INVISIBLE (1723 3900);
FORCEPROP 2 LAST CDS_LIB mstr_standard
J 0
(1725 3900);
PAINT ORANGE (1725 3900);
DISPLAY INVISIBLE (1725 3900);
FORCEPROP 1 LAST BODY_TYPE PLUMBING
J 0
(1775 3850);
DISPLAY 2.276596 (1775 3850);
PAINT GREEN (1775 3850);
DISPLAY INVISIBLE (1775 3850);
FORCEPROP 1 LAST HDL_TAP TRUE
J 0
(2045 3770);
DISPLAY 2.276596 (2045 3770);
PAINT GREEN (2045 3770);
DISPLAY INVISIBLE (2045 3770);
FORCEADD CAP..1
R 2
(1275 4350);
FORCEPROP 1 LASTPIN (1275 4450) $PN 1
J 2
(1265 4430);
DISPLAY 0.617021 (1265 4430);
PAINT ORANGE (1265 4430);
FORCEPROP 1 LASTPIN (1275 4250) $PN 2
J 2
(1265 4230);
DISPLAY 0.617021 (1265 4230);
PAINT ORANGE (1265 4230);
FORCEPROP 1 LAST MATERIAL X7R
J 2
(1225 4250);
DISPLAY 0.617021 (1225 4250);
PAINT SKYBLUE (1225 4250);
FORCEPROP 1 LAST VOLTAGE 16V
J 2
(1225 4350);
DISPLAY 0.617021 (1225 4350);
PAINT SKYBLUE (1225 4350);
FORCEPROP 1 LAST PACK_TYPE 0402
J 2
(1225 4150);
DISPLAY 0.617021 (1225 4150);
PAINT SKYBLUE (1225 4150);
FORCEPROP 1 LAST TOLERANCE 10%
J 2
(1225 4300);
DISPLAY 0.617021 (1225 4300);
PAINT SKYBLUE (1225 4300);
FORCEPROP 1 LAST VALUE 0.22UF
J 2
(1225 4400);
DISPLAY 0.617021 (1225 4400);
PAINT SKYBLUE (1225 4400);
FORCEPROP 1 LAST PART_NUMBER A36096-155
J 2
(1225 4200);
DISPLAY 0.617021 (1225 4200);
PAINT BLUE (1225 4200);
FORCEPROP 1 LAST LOCATION C7G25
J 2
(1225 4450);
DISPLAY 0.617021 (1225 4450);
PAINT AQUA (1225 4450);
FORCEPROP 2 LAST ROOM OCP_STEERING
J 2
(1275 4350);
PAINT MONO (1275 4350);
DISPLAY INVISIBLE (1275 4350);
FORCEPROP 1 LAST PATH I69
J 2
(1225 4500);
DISPLAY 0.978723 (1225 4500);
PAINT WHITE (1225 4500);
DISPLAY INVISIBLE (1225 4500);
FORCEPROP 2 LAST CDS_LOCATION C7G25
J 2
(1225 4450);
DISPLAY 0.617021 (1225 4450);
PAINT AQUA (1225 4450);
DISPLAY INVISIBLE (1225 4450);
FORCEPROP 2 LAST SEC 1
J 0
(1225 4550);
DISPLAY 0.680851 (1225 4550);
PAINT MONO (1225 4550);
DISPLAY INVISIBLE (1225 4550);
FORCEPROP 2 LAST SEC_TYPE 0402
J 0
(1225 4550);
DISPLAY 1.021277 (1225 4550);
PAINT ORANGE (1225 4550);
DISPLAY INVISIBLE (1225 4550);
FORCEPROP 2 LAST CDS_LIB mstr_discrete
J 0
(1275 4350);
PAINT ORANGE (1275 4350);
DISPLAY INVISIBLE (1275 4350);
FORCEADD CAP..1
R 2
(-500 3650);
FORCEPROP 1 LASTPIN (-500 3750) $PN 1
J 2
(-510 3730);
DISPLAY 0.617021 (-510 3730);
PAINT ORANGE (-510 3730);
FORCEPROP 1 LASTPIN (-500 3550) $PN 2
J 2
(-510 3530);
DISPLAY 0.617021 (-510 3530);
PAINT ORANGE (-510 3530);
FORCEPROP 1 LAST MATERIAL X7R
J 2
(-550 3550);
DISPLAY 0.617021 (-550 3550);
PAINT SKYBLUE (-550 3550);
FORCEPROP 1 LAST VOLTAGE 16V
J 2
(-550 3650);
DISPLAY 0.617021 (-550 3650);
PAINT SKYBLUE (-550 3650);
FORCEPROP 1 LAST PACK_TYPE 0402
J 2
(-550 3450);
DISPLAY 0.617021 (-550 3450);
PAINT SKYBLUE (-550 3450);
FORCEPROP 1 LAST TOLERANCE 10%
J 2
(-550 3600);
DISPLAY 0.617021 (-550 3600);
PAINT SKYBLUE (-550 3600);
FORCEPROP 1 LAST VALUE 0.22UF
J 2
(-550 3700);
DISPLAY 0.617021 (-550 3700);
PAINT SKYBLUE (-550 3700);
FORCEPROP 1 LAST PART_NUMBER A36096-155
J 2
(-550 3500);
DISPLAY 0.617021 (-550 3500);
PAINT BLUE (-550 3500);
FORCEPROP 1 LAST LOCATION C7G7
J 2
(-550 3750);
DISPLAY 0.617021 (-550 3750);
PAINT AQUA (-550 3750);
FORCEPROP 2 LAST ROOM OCP_STEERING
J 2
(-500 3650);
PAINT MONO (-500 3650);
DISPLAY INVISIBLE (-500 3650);
FORCEPROP 1 LAST PATH I7
J 2
(-550 3800);
DISPLAY 0.978723 (-550 3800);
PAINT WHITE (-550 3800);
DISPLAY INVISIBLE (-550 3800);
FORCEPROP 2 LAST CDS_LOCATION C7G7
J 2
(-550 3750);
DISPLAY 0.617021 (-550 3750);
PAINT AQUA (-550 3750);
DISPLAY INVISIBLE (-550 3750);
FORCEPROP 2 LAST SEC 1
J 0
(-550 3850);
DISPLAY 0.680851 (-550 3850);
PAINT MONO (-550 3850);
DISPLAY INVISIBLE (-550 3850);
FORCEPROP 2 LAST CDS_LIB mstr_discrete
J 0
(-500 3650);
PAINT ORANGE (-500 3650);
DISPLAY INVISIBLE (-500 3650);
FORCEPROP 2 LAST SEC_TYPE 0402
J 0
(-550 3850);
DISPLAY 1.021277 (-550 3850);
PAINT ORANGE (-550 3850);
DISPLAY INVISIBLE (-550 3850);
FORCEADD CAP..1
R 2
(1475 4650);
FORCEPROP 1 LASTPIN (1475 4550) $PN 2
J 2
(1465 4530);
DISPLAY 0.617021 (1465 4530);
PAINT ORANGE (1465 4530);
FORCEPROP 1 LAST MATERIAL X7R
J 2
(1425 4550);
DISPLAY 0.617021 (1425 4550);
PAINT SKYBLUE (1425 4550);
FORCEPROP 1 LAST VOLTAGE 16V
J 2
(1425 4650);
DISPLAY 0.617021 (1425 4650);
PAINT SKYBLUE (1425 4650);
FORCEPROP 1 LAST PACK_TYPE 0402
J 2
(1425 4450);
DISPLAY 0.617021 (1425 4450);
PAINT SKYBLUE (1425 4450);
FORCEPROP 1 LAST TOLERANCE 10%
J 2
(1425 4600);
DISPLAY 0.617021 (1425 4600);
PAINT SKYBLUE (1425 4600);
FORCEPROP 1 LAST VALUE 0.22UF
J 2
(1425 4700);
DISPLAY 0.617021 (1425 4700);
PAINT SKYBLUE (1425 4700);
FORCEPROP 1 LASTPIN (1475 4750) $PN 1
J 2
(1465 4730);
DISPLAY 0.617021 (1465 4730);
PAINT ORANGE (1465 4730);
FORCEPROP 1 LAST LOCATION C8G1
J 2
(1425 4750);
DISPLAY 0.617021 (1425 4750);
PAINT AQUA (1425 4750);
FORCEPROP 1 LAST PART_NUMBER A36096-155
J 2
(1425 4500);
DISPLAY 0.617021 (1425 4500);
PAINT BLUE (1425 4500);
FORCEPROP 2 LAST ROOM OCP_STEERING
J 2
(1475 4650);
PAINT MONO (1475 4650);
DISPLAY INVISIBLE (1475 4650);
FORCEPROP 1 LAST PATH I70
J 2
(1425 4800);
DISPLAY 0.978723 (1425 4800);
PAINT WHITE (1425 4800);
DISPLAY INVISIBLE (1425 4800);
FORCEPROP 2 LAST CDS_LOCATION C8G1
J 2
(1425 4750);
DISPLAY 0.617021 (1425 4750);
PAINT AQUA (1425 4750);
DISPLAY INVISIBLE (1425 4750);
FORCEPROP 2 LAST SEC 1
J 0
(1425 4850);
DISPLAY 0.680851 (1425 4850);
PAINT MONO (1425 4850);
DISPLAY INVISIBLE (1425 4850);
FORCEPROP 2 LAST SEC_TYPE 0402
J 0
(1425 4850);
DISPLAY 1.021277 (1425 4850);
PAINT ORANGE (1425 4850);
DISPLAY INVISIBLE (1425 4850);
FORCEPROP 2 LAST CDS_LIB mstr_discrete
J 0
(1475 4650);
PAINT ORANGE (1475 4650);
DISPLAY INVISIBLE (1475 4650);
FORCEADD CAP..1
R 2
(1675 4350);
FORCEPROP 1 LASTPIN (1675 4450) $PN 1
J 2
(1665 4430);
DISPLAY 0.617021 (1665 4430);
PAINT ORANGE (1665 4430);
FORCEPROP 1 LASTPIN (1675 4250) $PN 2
J 2
(1665 4230);
DISPLAY 0.617021 (1665 4230);
PAINT ORANGE (1665 4230);
FORCEPROP 1 LAST MATERIAL X7R
J 2
(1625 4250);
DISPLAY 0.617021 (1625 4250);
PAINT SKYBLUE (1625 4250);
FORCEPROP 1 LAST VOLTAGE 16V
J 2
(1625 4350);
DISPLAY 0.617021 (1625 4350);
PAINT SKYBLUE (1625 4350);
FORCEPROP 1 LAST TOLERANCE 10%
J 2
(1625 4300);
DISPLAY 0.617021 (1625 4300);
PAINT SKYBLUE (1625 4300);
FORCEPROP 1 LAST VALUE 0.22UF
J 2
(1625 4400);
DISPLAY 0.617021 (1625 4400);
PAINT SKYBLUE (1625 4400);
FORCEPROP 1 LAST LOCATION C8G3
J 2
(1625 4450);
DISPLAY 0.617021 (1625 4450);
PAINT AQUA (1625 4450);
FORCEPROP 1 LAST PART_NUMBER A36096-155
J 2
(1625 4200);
DISPLAY 0.617021 (1625 4200);
PAINT BLUE (1625 4200);
FORCEPROP 1 LAST PACK_TYPE 0402
J 2
(1625 4150);
DISPLAY 0.617021 (1625 4150);
PAINT SKYBLUE (1625 4150);
FORCEPROP 2 LAST ROOM OCP_STEERING
J 2
(1675 4350);
PAINT MONO (1675 4350);
DISPLAY INVISIBLE (1675 4350);
FORCEPROP 1 LAST PATH I71
J 2
(1625 4500);
DISPLAY 0.978723 (1625 4500);
PAINT WHITE (1625 4500);
DISPLAY INVISIBLE (1625 4500);
FORCEPROP 2 LAST CDS_LOCATION C8G3
J 2
(1625 4450);
DISPLAY 0.617021 (1625 4450);
PAINT AQUA (1625 4450);
DISPLAY INVISIBLE (1625 4450);
FORCEPROP 2 LAST SEC 1
J 0
(1625 4550);
DISPLAY 0.680851 (1625 4550);
PAINT MONO (1625 4550);
DISPLAY INVISIBLE (1625 4550);
FORCEPROP 2 LAST SEC_TYPE 0402
J 0
(1625 4550);
DISPLAY 1.021277 (1625 4550);
PAINT ORANGE (1625 4550);
DISPLAY INVISIBLE (1625 4550);
FORCEPROP 2 LAST CDS_LIB mstr_discrete
J 0
(1675 4350);
PAINT ORANGE (1675 4350);
DISPLAY INVISIBLE (1675 4350);
FORCEADD TAP..7
(1875 4100);
FORCEPROP 3 LASTPIN (1875 4150) SIG_NAME P3E_CPU0_PE2_SS_C_TXP<2>
J 0
(1885 4160);
DISPLAY 0.659574 (1885 4160);
PAINT MONO (1885 4160);
DISPLAY INVISIBLE (1885 4160);
FORCEPROP 1 LASTPIN (1875 4150) BN 2
R 1
J 0
(1868 4098);
DISPLAY 0.617021 (1868 4098);
PAINT GREEN (1868 4098);
FORCEPROP 1 LAST PATH I72
J 0
(1873 4100);
DISPLAY 0.872340 (1873 4100);
PAINT GREEN (1873 4100);
DISPLAY INVISIBLE (1873 4100);
FORCEPROP 2 LAST CDS_LIB mstr_standard
J 0
(1875 4100);
PAINT ORANGE (1875 4100);
DISPLAY INVISIBLE (1875 4100);
FORCEPROP 1 LAST BODY_TYPE PLUMBING
J 0
(1925 4100);
DISPLAY 2.276596 (1925 4100);
PAINT GREEN (1925 4100);
DISPLAY INVISIBLE (1925 4100);
FORCEPROP 1 LAST HDL_TAP TRUE
J 0
(2195 3970);
DISPLAY 2.276596 (2195 3970);
PAINT GREEN (2195 3970);
DISPLAY INVISIBLE (2195 3970);
FORCEADD TAP..3
(2125 3900);
FORCEPROP 3 LASTPIN (2125 3850) SIG_NAME P3E_CPU0_PE2_SS_TXN<1>
J 0
(2135 3860);
DISPLAY 0.659574 (2135 3860);
PAINT MONO (2135 3860);
DISPLAY INVISIBLE (2135 3860);
FORCEPROP 1 LASTPIN (2125 3850) BN 1
R 1
J 0
(2118 3838);
DISPLAY 0.617021 (2118 3838);
PAINT GREEN (2118 3838);
FORCEPROP 1 LAST PATH I73
J 0
(2123 3900);
DISPLAY 0.872340 (2123 3900);
PAINT GREEN (2123 3900);
DISPLAY INVISIBLE (2123 3900);
FORCEPROP 2 LAST CDS_LIB mstr_standard
J 0
(2125 3900);
PAINT ORANGE (2125 3900);
DISPLAY INVISIBLE (2125 3900);
FORCEPROP 1 LAST BODY_TYPE PLUMBING
J 0
(2175 3850);
DISPLAY 2.276596 (2175 3850);
PAINT GREEN (2175 3850);
DISPLAY INVISIBLE (2175 3850);
FORCEPROP 1 LAST HDL_TAP TRUE
J 0
(2445 3770);
DISPLAY 2.276596 (2445 3770);
PAINT GREEN (2445 3770);
DISPLAY INVISIBLE (2445 3770);
FORCEADD TAP..7
(2075 4100);
FORCEPROP 3 LASTPIN (2075 4150) SIG_NAME P3E_CPU0_PE2_SS_C_TXP<1>
J 0
(2085 4160);
DISPLAY 0.659574 (2085 4160);
PAINT MONO (2085 4160);
DISPLAY INVISIBLE (2085 4160);
FORCEPROP 1 LASTPIN (2075 4150) BN 1
R 1
J 0
(2068 4098);
DISPLAY 0.617021 (2068 4098);
PAINT GREEN (2068 4098);
FORCEPROP 1 LAST PATH I74
J 0
(2073 4100);
DISPLAY 0.872340 (2073 4100);
PAINT GREEN (2073 4100);
DISPLAY INVISIBLE (2073 4100);
FORCEPROP 2 LAST CDS_LIB mstr_standard
J 0
(2075 4100);
PAINT ORANGE (2075 4100);
DISPLAY INVISIBLE (2075 4100);
FORCEPROP 1 LAST BODY_TYPE PLUMBING
J 0
(2125 4100);
DISPLAY 2.276596 (2125 4100);
PAINT GREEN (2125 4100);
DISPLAY INVISIBLE (2125 4100);
FORCEPROP 1 LAST HDL_TAP TRUE
J 0
(2395 3970);
DISPLAY 2.276596 (2395 3970);
PAINT GREEN (2395 3970);
DISPLAY INVISIBLE (2395 3970);
FORCEADD CAP..1
R 2
(1875 4650);
FORCEPROP 1 LASTPIN (1875 4550) $PN 2
J 2
(1865 4530);
DISPLAY 0.617021 (1865 4530);
PAINT ORANGE (1865 4530);
FORCEPROP 1 LAST MATERIAL X7R
J 2
(1825 4550);
DISPLAY 0.617021 (1825 4550);
PAINT SKYBLUE (1825 4550);
FORCEPROP 1 LAST VOLTAGE 16V
J 2
(1825 4650);
DISPLAY 0.617021 (1825 4650);
PAINT SKYBLUE (1825 4650);
FORCEPROP 1 LAST PACK_TYPE 0402
J 2
(1825 4450);
DISPLAY 0.617021 (1825 4450);
PAINT SKYBLUE (1825 4450);
FORCEPROP 1 LAST TOLERANCE 10%
J 2
(1825 4600);
DISPLAY 0.617021 (1825 4600);
PAINT SKYBLUE (1825 4600);
FORCEPROP 1 LAST VALUE 0.22UF
J 2
(1825 4700);
DISPLAY 0.617021 (1825 4700);
PAINT SKYBLUE (1825 4700);
FORCEPROP 1 LASTPIN (1875 4750) $PN 1
J 2
(1865 4730);
DISPLAY 0.617021 (1865 4730);
PAINT ORANGE (1865 4730);
FORCEPROP 1 LAST LOCATION C8G5
J 2
(1825 4750);
DISPLAY 0.617021 (1825 4750);
PAINT AQUA (1825 4750);
FORCEPROP 1 LAST PART_NUMBER A36096-155
J 2
(1825 4500);
DISPLAY 0.617021 (1825 4500);
PAINT BLUE (1825 4500);
FORCEPROP 2 LAST ROOM OCP_STEERING
J 2
(1875 4650);
PAINT MONO (1875 4650);
DISPLAY INVISIBLE (1875 4650);
FORCEPROP 1 LAST PATH I75
J 2
(1825 4800);
DISPLAY 0.978723 (1825 4800);
PAINT WHITE (1825 4800);
DISPLAY INVISIBLE (1825 4800);
FORCEPROP 2 LAST CDS_LOCATION C8G5
J 2
(1825 4750);
DISPLAY 0.617021 (1825 4750);
PAINT AQUA (1825 4750);
DISPLAY INVISIBLE (1825 4750);
FORCEPROP 2 LAST SEC 1
J 0
(1825 4850);
DISPLAY 0.680851 (1825 4850);
PAINT MONO (1825 4850);
DISPLAY INVISIBLE (1825 4850);
FORCEPROP 2 LAST SEC_TYPE 0402
J 0
(1825 4850);
DISPLAY 1.021277 (1825 4850);
PAINT ORANGE (1825 4850);
DISPLAY INVISIBLE (1825 4850);
FORCEPROP 2 LAST CDS_LIB mstr_discrete
J 0
(1875 4650);
PAINT ORANGE (1875 4650);
DISPLAY INVISIBLE (1875 4650);
FORCEADD CAP..1
R 2
(2075 4350);
FORCEPROP 1 LASTPIN (2075 4450) $PN 1
J 2
(2065 4430);
DISPLAY 0.617021 (2065 4430);
PAINT ORANGE (2065 4430);
FORCEPROP 1 LASTPIN (2075 4250) $PN 2
J 2
(2065 4230);
DISPLAY 0.617021 (2065 4230);
PAINT ORANGE (2065 4230);
FORCEPROP 1 LAST MATERIAL X7R
J 2
(2025 4250);
DISPLAY 0.617021 (2025 4250);
PAINT SKYBLUE (2025 4250);
FORCEPROP 1 LAST PACK_TYPE 0402
J 2
(2025 4150);
DISPLAY 0.617021 (2025 4150);
PAINT SKYBLUE (2025 4150);
FORCEPROP 1 LAST VALUE 0.22UF
J 2
(2025 4400);
DISPLAY 0.617021 (2025 4400);
PAINT SKYBLUE (2025 4400);
FORCEPROP 1 LAST LOCATION C8G8
J 2
(2025 4450);
DISPLAY 0.617021 (2025 4450);
PAINT AQUA (2025 4450);
FORCEPROP 1 LAST VOLTAGE 16V
J 2
(2025 4350);
DISPLAY 0.617021 (2025 4350);
PAINT SKYBLUE (2025 4350);
FORCEPROP 1 LAST TOLERANCE 10%
J 2
(2025 4300);
DISPLAY 0.617021 (2025 4300);
PAINT SKYBLUE (2025 4300);
FORCEPROP 1 LAST PART_NUMBER A36096-155
J 2
(2025 4200);
DISPLAY 0.617021 (2025 4200);
PAINT BLUE (2025 4200);
FORCEPROP 2 LAST ROOM OCP_STEERING
J 2
(2075 4350);
PAINT MONO (2075 4350);
DISPLAY INVISIBLE (2075 4350);
FORCEPROP 1 LAST PATH I76
J 2
(2025 4500);
DISPLAY 0.978723 (2025 4500);
PAINT WHITE (2025 4500);
DISPLAY INVISIBLE (2025 4500);
FORCEPROP 2 LAST CDS_LOCATION C8G8
J 2
(2025 4450);
DISPLAY 0.617021 (2025 4450);
PAINT AQUA (2025 4450);
DISPLAY INVISIBLE (2025 4450);
FORCEPROP 2 LAST SEC 1
J 0
(2025 4550);
DISPLAY 0.680851 (2025 4550);
PAINT MONO (2025 4550);
DISPLAY INVISIBLE (2025 4550);
FORCEPROP 2 LAST SEC_TYPE 0402
J 0
(2025 4550);
DISPLAY 1.021277 (2025 4550);
PAINT ORANGE (2025 4550);
DISPLAY INVISIBLE (2025 4550);
FORCEPROP 2 LAST CDS_LIB mstr_discrete
J 0
(2075 4350);
PAINT ORANGE (2075 4350);
DISPLAY INVISIBLE (2075 4350);
FORCEADD OFFPAGE..1
(-925 4950);
FORCEPROP 2 LAST $XR0 31 
J 0
(-1176 4950);
DISPLAY 0.638298 (-1176 4950);
PAINT MONO (-1176 4950);
FORCEPROP 2 LAST PATH I77
J 0
(-1125 5000);
DISPLAY 1.021277 (-1125 5000);
PAINT ORANGE (-1125 5000);
DISPLAY INVISIBLE (-1125 5000);
FORCEPROP 2 LAST CDS_LIB mstr_standard
J 0
(-925 4950);
PAINT ORANGE (-925 4950);
DISPLAY INVISIBLE (-925 4950);
FORCEPROP 1 LAST OFFPAGE TRUE
J 0
(-605 4820);
PAINT GREEN (-605 4820);
DISPLAY INVISIBLE (-605 4820);
FORCEPROP 1 LAST COMMENT_BODY TRUE
J 0
(-805 4850);
DISPLAY 2.276596 (-805 4850);
PAINT GREEN (-805 4850);
DISPLAY INVISIBLE (-805 4850);
FORCEADD TAP..3
(-750 4900);
FORCEPROP 3 LASTPIN (-750 4850) SIG_NAME P3E_CPU0_PE2_SS_TXP<15>
J 0
(-740 4860);
DISPLAY 0.659574 (-740 4860);
PAINT MONO (-740 4860);
DISPLAY INVISIBLE (-740 4860);
FORCEPROP 1 LASTPIN (-750 4850) BN 15
R 1
J 0
(-757 4838);
DISPLAY 0.617021 (-757 4838);
PAINT GREEN (-757 4838);
FORCEPROP 1 LAST PATH I78
J 0
(-752 4900);
DISPLAY 0.872340 (-752 4900);
PAINT GREEN (-752 4900);
DISPLAY INVISIBLE (-752 4900);
FORCEPROP 2 LAST CDS_LIB mstr_standard
J 0
(-750 4900);
PAINT ORANGE (-750 4900);
DISPLAY INVISIBLE (-750 4900);
FORCEPROP 1 LAST BODY_TYPE PLUMBING
J 0
(-700 4850);
DISPLAY 2.276596 (-700 4850);
PAINT GREEN (-700 4850);
DISPLAY INVISIBLE (-700 4850);
FORCEPROP 1 LAST HDL_TAP TRUE
J 0
(-430 4770);
DISPLAY 2.276596 (-430 4770);
PAINT GREEN (-430 4770);
DISPLAY INVISIBLE (-430 4770);
FORCEADD TAP..3
(-550 4900);
FORCEPROP 3 LASTPIN (-550 4850) SIG_NAME P3E_CPU0_PE2_SS_TXP<14>
J 0
(-540 4860);
DISPLAY 0.659574 (-540 4860);
PAINT MONO (-540 4860);
DISPLAY INVISIBLE (-540 4860);
FORCEPROP 1 LASTPIN (-550 4850) BN 14
R 1
J 0
(-557 4838);
DISPLAY 0.617021 (-557 4838);
PAINT GREEN (-557 4838);
FORCEPROP 1 LAST PATH I79
J 0
(-552 4900);
DISPLAY 0.872340 (-552 4900);
PAINT GREEN (-552 4900);
DISPLAY INVISIBLE (-552 4900);
FORCEPROP 2 LAST CDS_LIB mstr_standard
J 0
(-550 4900);
PAINT ORANGE (-550 4900);
DISPLAY INVISIBLE (-550 4900);
FORCEPROP 1 LAST BODY_TYPE PLUMBING
J 0
(-500 4850);
DISPLAY 2.276596 (-500 4850);
PAINT GREEN (-500 4850);
DISPLAY INVISIBLE (-500 4850);
FORCEPROP 1 LAST HDL_TAP TRUE
J 0
(-230 4770);
DISPLAY 2.276596 (-230 4770);
PAINT GREEN (-230 4770);
DISPLAY INVISIBLE (-230 4770);
FORCEADD CAP..1
R 2
(-300 3350);
FORCEPROP 1 LASTPIN (-300 3450) $PN 1
J 2
(-310 3430);
DISPLAY 0.617021 (-310 3430);
PAINT ORANGE (-310 3430);
FORCEPROP 1 LASTPIN (-300 3250) $PN 2
J 2
(-310 3230);
DISPLAY 0.617021 (-310 3230);
PAINT ORANGE (-310 3230);
FORCEPROP 1 LAST MATERIAL X7R
J 2
(-350 3250);
DISPLAY 0.617021 (-350 3250);
PAINT SKYBLUE (-350 3250);
FORCEPROP 1 LAST VOLTAGE 16V
J 2
(-350 3350);
DISPLAY 0.617021 (-350 3350);
PAINT SKYBLUE (-350 3350);
FORCEPROP 1 LAST TOLERANCE 10%
J 2
(-350 3300);
DISPLAY 0.617021 (-350 3300);
PAINT SKYBLUE (-350 3300);
FORCEPROP 1 LAST VALUE 0.22UF
J 2
(-350 3400);
DISPLAY 0.617021 (-350 3400);
PAINT SKYBLUE (-350 3400);
FORCEPROP 1 LAST PART_NUMBER A36096-155
J 2
(-350 3200);
DISPLAY 0.617021 (-350 3200);
PAINT BLUE (-350 3200);
FORCEPROP 1 LAST LOCATION C7G10
J 2
(-350 3450);
DISPLAY 0.617021 (-350 3450);
PAINT AQUA (-350 3450);
FORCEPROP 1 LAST PACK_TYPE 0402
J 2
(-350 3150);
DISPLAY 0.617021 (-350 3150);
PAINT SKYBLUE (-350 3150);
FORCEPROP 2 LAST ROOM OCP_STEERING
J 2
(-300 3350);
PAINT MONO (-300 3350);
DISPLAY INVISIBLE (-300 3350);
FORCEPROP 1 LAST PATH I8
J 2
(-350 3500);
DISPLAY 0.978723 (-350 3500);
PAINT WHITE (-350 3500);
DISPLAY INVISIBLE (-350 3500);
FORCEPROP 2 LAST CDS_LOCATION C7G10
J 2
(-350 3450);
DISPLAY 0.617021 (-350 3450);
PAINT AQUA (-350 3450);
DISPLAY INVISIBLE (-350 3450);
FORCEPROP 2 LAST SEC 1
J 0
(-350 3550);
DISPLAY 0.680851 (-350 3550);
PAINT MONO (-350 3550);
DISPLAY INVISIBLE (-350 3550);
FORCEPROP 2 LAST CDS_LIB mstr_discrete
J 0
(-300 3350);
PAINT ORANGE (-300 3350);
DISPLAY INVISIBLE (-300 3350);
FORCEPROP 2 LAST SEC_TYPE 0402
J 0
(-350 3550);
DISPLAY 1.021277 (-350 3550);
PAINT ORANGE (-350 3550);
DISPLAY INVISIBLE (-350 3550);
FORCEADD TAP..3
(-350 4900);
FORCEPROP 3 LASTPIN (-350 4850) SIG_NAME P3E_CPU0_PE2_SS_TXP<13>
J 0
(-340 4860);
DISPLAY 0.659574 (-340 4860);
PAINT MONO (-340 4860);
DISPLAY INVISIBLE (-340 4860);
FORCEPROP 1 LASTPIN (-350 4850) BN 13
R 1
J 0
(-357 4838);
DISPLAY 0.617021 (-357 4838);
PAINT GREEN (-357 4838);
FORCEPROP 1 LAST PATH I80
J 0
(-352 4900);
DISPLAY 0.872340 (-352 4900);
PAINT GREEN (-352 4900);
DISPLAY INVISIBLE (-352 4900);
FORCEPROP 2 LAST CDS_LIB mstr_standard
J 0
(-350 4900);
PAINT ORANGE (-350 4900);
DISPLAY INVISIBLE (-350 4900);
FORCEPROP 1 LAST BODY_TYPE PLUMBING
J 0
(-300 4850);
DISPLAY 2.276596 (-300 4850);
PAINT GREEN (-300 4850);
DISPLAY INVISIBLE (-300 4850);
FORCEPROP 1 LAST HDL_TAP TRUE
J 0
(-30 4770);
DISPLAY 2.276596 (-30 4770);
PAINT GREEN (-30 4770);
DISPLAY INVISIBLE (-30 4770);
FORCEADD TAP..3
(-150 4900);
FORCEPROP 3 LASTPIN (-150 4850) SIG_NAME P3E_CPU0_PE2_SS_TXP<12>
J 0
(-140 4860);
DISPLAY 0.659574 (-140 4860);
PAINT MONO (-140 4860);
DISPLAY INVISIBLE (-140 4860);
FORCEPROP 1 LASTPIN (-150 4850) BN 12
R 1
J 0
(-157 4838);
DISPLAY 0.617021 (-157 4838);
PAINT GREEN (-157 4838);
FORCEPROP 1 LAST PATH I81
J 0
(-152 4900);
DISPLAY 0.872340 (-152 4900);
PAINT GREEN (-152 4900);
DISPLAY INVISIBLE (-152 4900);
FORCEPROP 2 LAST CDS_LIB mstr_standard
J 0
(-150 4900);
PAINT ORANGE (-150 4900);
DISPLAY INVISIBLE (-150 4900);
FORCEPROP 1 LAST BODY_TYPE PLUMBING
J 0
(-100 4850);
DISPLAY 2.276596 (-100 4850);
PAINT GREEN (-100 4850);
DISPLAY INVISIBLE (-100 4850);
FORCEPROP 1 LAST HDL_TAP TRUE
J 0
(170 4770);
DISPLAY 2.276596 (170 4770);
PAINT GREEN (170 4770);
DISPLAY INVISIBLE (170 4770);
FORCEADD TAP..3
(450 4900);
FORCEPROP 3 LASTPIN (450 4850) SIG_NAME P3E_CPU0_PE2_SS_TXP<9>
J 0
(460 4860);
DISPLAY 0.659574 (460 4860);
PAINT MONO (460 4860);
DISPLAY INVISIBLE (460 4860);
FORCEPROP 1 LASTPIN (450 4850) BN 9
R 1
J 0
(443 4838);
DISPLAY 0.617021 (443 4838);
PAINT GREEN (443 4838);
FORCEPROP 1 LAST PATH I82
J 0
(448 4900);
DISPLAY 0.872340 (448 4900);
PAINT GREEN (448 4900);
DISPLAY INVISIBLE (448 4900);
FORCEPROP 2 LAST CDS_LIB mstr_standard
J 0
(450 4900);
PAINT ORANGE (450 4900);
DISPLAY INVISIBLE (450 4900);
FORCEPROP 1 LAST BODY_TYPE PLUMBING
J 0
(500 4850);
DISPLAY 2.276596 (500 4850);
PAINT GREEN (500 4850);
DISPLAY INVISIBLE (500 4850);
FORCEPROP 1 LAST HDL_TAP TRUE
J 0
(770 4770);
DISPLAY 2.276596 (770 4770);
PAINT GREEN (770 4770);
DISPLAY INVISIBLE (770 4770);
FORCEADD TAP..3
(250 4900);
FORCEPROP 3 LASTPIN (250 4850) SIG_NAME P3E_CPU0_PE2_SS_TXP<10>
J 0
(260 4860);
DISPLAY 0.659574 (260 4860);
PAINT MONO (260 4860);
DISPLAY INVISIBLE (260 4860);
FORCEPROP 1 LASTPIN (250 4850) BN 10
R 1
J 0
(243 4838);
DISPLAY 0.617021 (243 4838);
PAINT GREEN (243 4838);
FORCEPROP 1 LAST PATH I83
J 0
(248 4900);
DISPLAY 0.872340 (248 4900);
PAINT GREEN (248 4900);
DISPLAY INVISIBLE (248 4900);
FORCEPROP 2 LAST CDS_LIB mstr_standard
J 0
(250 4900);
PAINT ORANGE (250 4900);
DISPLAY INVISIBLE (250 4900);
FORCEPROP 1 LAST BODY_TYPE PLUMBING
J 0
(300 4850);
DISPLAY 2.276596 (300 4850);
PAINT GREEN (300 4850);
DISPLAY INVISIBLE (300 4850);
FORCEPROP 1 LAST HDL_TAP TRUE
J 0
(570 4770);
DISPLAY 2.276596 (570 4770);
PAINT GREEN (570 4770);
DISPLAY INVISIBLE (570 4770);
FORCEADD TAP..3
(650 4900);
FORCEPROP 3 LASTPIN (650 4850) SIG_NAME P3E_CPU0_PE2_SS_TXP<8>
J 0
(660 4860);
DISPLAY 0.659574 (660 4860);
PAINT MONO (660 4860);
DISPLAY INVISIBLE (660 4860);
FORCEPROP 1 LASTPIN (650 4850) BN 8
R 1
J 0
(643 4838);
DISPLAY 0.617021 (643 4838);
PAINT GREEN (643 4838);
FORCEPROP 1 LAST PATH I84
J 0
(648 4900);
DISPLAY 0.872340 (648 4900);
PAINT GREEN (648 4900);
DISPLAY INVISIBLE (648 4900);
FORCEPROP 2 LAST CDS_LIB mstr_standard
J 0
(650 4900);
PAINT ORANGE (650 4900);
DISPLAY INVISIBLE (650 4900);
FORCEPROP 1 LAST BODY_TYPE PLUMBING
J 0
(700 4850);
DISPLAY 2.276596 (700 4850);
PAINT GREEN (700 4850);
DISPLAY INVISIBLE (700 4850);
FORCEPROP 1 LAST HDL_TAP TRUE
J 0
(970 4770);
DISPLAY 2.276596 (970 4770);
PAINT GREEN (970 4770);
DISPLAY INVISIBLE (970 4770);
FORCEADD TAP..3
(875 4900);
FORCEPROP 3 LASTPIN (875 4850) SIG_NAME P3E_CPU0_PE2_SS_TXP<7>
J 0
(885 4860);
DISPLAY 0.659574 (885 4860);
PAINT MONO (885 4860);
DISPLAY INVISIBLE (885 4860);
FORCEPROP 1 LASTPIN (875 4850) BN 7
R 1
J 0
(868 4838);
DISPLAY 0.617021 (868 4838);
PAINT GREEN (868 4838);
FORCEPROP 1 LAST PATH I85
J 0
(873 4900);
DISPLAY 0.872340 (873 4900);
PAINT GREEN (873 4900);
DISPLAY INVISIBLE (873 4900);
FORCEPROP 2 LAST CDS_LIB mstr_standard
J 0
(875 4900);
PAINT ORANGE (875 4900);
DISPLAY INVISIBLE (875 4900);
FORCEPROP 1 LAST BODY_TYPE PLUMBING
J 0
(925 4850);
DISPLAY 2.276596 (925 4850);
PAINT GREEN (925 4850);
DISPLAY INVISIBLE (925 4850);
FORCEPROP 1 LAST HDL_TAP TRUE
J 0
(1195 4770);
DISPLAY 2.276596 (1195 4770);
PAINT GREEN (1195 4770);
DISPLAY INVISIBLE (1195 4770);
FORCEADD TAP..3
(1075 4900);
FORCEPROP 3 LASTPIN (1075 4850) SIG_NAME P3E_CPU0_PE2_SS_TXP<6>
J 0
(1085 4860);
DISPLAY 0.659574 (1085 4860);
PAINT MONO (1085 4860);
DISPLAY INVISIBLE (1085 4860);
FORCEPROP 1 LASTPIN (1075 4850) BN 6
R 1
J 0
(1068 4838);
DISPLAY 0.617021 (1068 4838);
PAINT GREEN (1068 4838);
FORCEPROP 1 LAST PATH I86
J 0
(1073 4900);
DISPLAY 0.872340 (1073 4900);
PAINT GREEN (1073 4900);
DISPLAY INVISIBLE (1073 4900);
FORCEPROP 2 LAST CDS_LIB mstr_standard
J 0
(1075 4900);
PAINT ORANGE (1075 4900);
DISPLAY INVISIBLE (1075 4900);
FORCEPROP 1 LAST BODY_TYPE PLUMBING
J 0
(1125 4850);
DISPLAY 2.276596 (1125 4850);
PAINT GREEN (1125 4850);
DISPLAY INVISIBLE (1125 4850);
FORCEPROP 1 LAST HDL_TAP TRUE
J 0
(1395 4770);
DISPLAY 2.276596 (1395 4770);
PAINT GREEN (1395 4770);
DISPLAY INVISIBLE (1395 4770);
FORCEADD TAP..3
(1275 4900);
FORCEPROP 3 LASTPIN (1275 4850) SIG_NAME P3E_CPU0_PE2_SS_TXP<5>
J 0
(1285 4860);
DISPLAY 0.659574 (1285 4860);
PAINT MONO (1285 4860);
DISPLAY INVISIBLE (1285 4860);
FORCEPROP 1 LASTPIN (1275 4850) BN 5
R 1
J 0
(1268 4838);
DISPLAY 0.617021 (1268 4838);
PAINT GREEN (1268 4838);
FORCEPROP 1 LAST PATH I87
J 0
(1273 4900);
DISPLAY 0.872340 (1273 4900);
PAINT GREEN (1273 4900);
DISPLAY INVISIBLE (1273 4900);
FORCEPROP 2 LAST CDS_LIB mstr_standard
J 0
(1275 4900);
PAINT ORANGE (1275 4900);
DISPLAY INVISIBLE (1275 4900);
FORCEPROP 1 LAST BODY_TYPE PLUMBING
J 0
(1325 4850);
DISPLAY 2.276596 (1325 4850);
PAINT GREEN (1325 4850);
DISPLAY INVISIBLE (1325 4850);
FORCEPROP 1 LAST HDL_TAP TRUE
J 0
(1595 4770);
DISPLAY 2.276596 (1595 4770);
PAINT GREEN (1595 4770);
DISPLAY INVISIBLE (1595 4770);
FORCEADD TAP..3
(1475 4900);
FORCEPROP 3 LASTPIN (1475 4850) SIG_NAME P3E_CPU0_PE2_SS_TXP<4>
J 0
(1485 4860);
DISPLAY 0.659574 (1485 4860);
PAINT MONO (1485 4860);
DISPLAY INVISIBLE (1485 4860);
FORCEPROP 1 LASTPIN (1475 4850) BN 4
R 1
J 0
(1468 4838);
DISPLAY 0.617021 (1468 4838);
PAINT GREEN (1468 4838);
FORCEPROP 1 LAST PATH I88
J 0
(1473 4900);
DISPLAY 0.872340 (1473 4900);
PAINT GREEN (1473 4900);
DISPLAY INVISIBLE (1473 4900);
FORCEPROP 2 LAST CDS_LIB mstr_standard
J 0
(1475 4900);
PAINT ORANGE (1475 4900);
DISPLAY INVISIBLE (1475 4900);
FORCEPROP 1 LAST BODY_TYPE PLUMBING
J 0
(1525 4850);
DISPLAY 2.276596 (1525 4850);
PAINT GREEN (1525 4850);
DISPLAY INVISIBLE (1525 4850);
FORCEPROP 1 LAST HDL_TAP TRUE
J 0
(1795 4770);
DISPLAY 2.276596 (1795 4770);
PAINT GREEN (1795 4770);
DISPLAY INVISIBLE (1795 4770);
FORCEADD TAP..3
(1675 4900);
FORCEPROP 3 LASTPIN (1675 4850) SIG_NAME P3E_CPU0_PE2_SS_TXP<3>
J 0
(1685 4860);
DISPLAY 0.659574 (1685 4860);
PAINT MONO (1685 4860);
DISPLAY INVISIBLE (1685 4860);
FORCEPROP 1 LASTPIN (1675 4850) BN 3
R 1
J 0
(1668 4838);
DISPLAY 0.617021 (1668 4838);
PAINT GREEN (1668 4838);
FORCEPROP 1 LAST PATH I89
J 0
(1673 4900);
DISPLAY 0.872340 (1673 4900);
PAINT GREEN (1673 4900);
DISPLAY INVISIBLE (1673 4900);
FORCEPROP 2 LAST CDS_LIB mstr_standard
J 0
(1675 4900);
PAINT ORANGE (1675 4900);
DISPLAY INVISIBLE (1675 4900);
FORCEPROP 1 LAST BODY_TYPE PLUMBING
J 0
(1725 4850);
DISPLAY 2.276596 (1725 4850);
PAINT GREEN (1725 4850);
DISPLAY INVISIBLE (1725 4850);
FORCEPROP 1 LAST HDL_TAP TRUE
J 0
(1995 4770);
DISPLAY 2.276596 (1995 4770);
PAINT GREEN (1995 4770);
DISPLAY INVISIBLE (1995 4770);
FORCEADD TAP..7
(-300 3100);
FORCEPROP 3 LASTPIN (-300 3150) SIG_NAME P3E_CPU0_PE2_SS_C_TXN<13>
J 0
(-290 3160);
DISPLAY 0.659574 (-290 3160);
PAINT MONO (-290 3160);
DISPLAY INVISIBLE (-290 3160);
FORCEPROP 1 LASTPIN (-300 3150) BN 13
R 1
J 0
(-307 3098);
DISPLAY 0.617021 (-307 3098);
PAINT GREEN (-307 3098);
FORCEPROP 1 LAST PATH I9
J 0
(-302 3100);
DISPLAY 0.872340 (-302 3100);
PAINT GREEN (-302 3100);
DISPLAY INVISIBLE (-302 3100);
FORCEPROP 2 LAST CDS_LIB mstr_standard
J 0
(-300 3100);
PAINT ORANGE (-300 3100);
DISPLAY INVISIBLE (-300 3100);
FORCEPROP 1 LAST BODY_TYPE PLUMBING
J 0
(-250 3100);
DISPLAY 2.276596 (-250 3100);
PAINT GREEN (-250 3100);
DISPLAY INVISIBLE (-250 3100);
FORCEPROP 1 LAST HDL_TAP TRUE
J 0
(20 2970);
DISPLAY 2.276596 (20 2970);
PAINT GREEN (20 2970);
DISPLAY INVISIBLE (20 2970);
FORCEADD TAP..3
(1875 4900);
FORCEPROP 3 LASTPIN (1875 4850) SIG_NAME P3E_CPU0_PE2_SS_TXP<2>
J 0
(1885 4860);
DISPLAY 0.659574 (1885 4860);
PAINT MONO (1885 4860);
DISPLAY INVISIBLE (1885 4860);
FORCEPROP 1 LASTPIN (1875 4850) BN 2
R 1
J 0
(1868 4838);
DISPLAY 0.617021 (1868 4838);
PAINT GREEN (1868 4838);
FORCEPROP 1 LAST PATH I90
J 0
(1873 4900);
DISPLAY 0.872340 (1873 4900);
PAINT GREEN (1873 4900);
DISPLAY INVISIBLE (1873 4900);
FORCEPROP 2 LAST CDS_LIB mstr_standard
J 0
(1875 4900);
PAINT ORANGE (1875 4900);
DISPLAY INVISIBLE (1875 4900);
FORCEPROP 1 LAST BODY_TYPE PLUMBING
J 0
(1925 4850);
DISPLAY 2.276596 (1925 4850);
PAINT GREEN (1925 4850);
DISPLAY INVISIBLE (1925 4850);
FORCEPROP 1 LAST HDL_TAP TRUE
J 0
(2195 4770);
DISPLAY 2.276596 (2195 4770);
PAINT GREEN (2195 4770);
DISPLAY INVISIBLE (2195 4770);
FORCEADD TAP..3
(2075 4900);
FORCEPROP 3 LASTPIN (2075 4850) SIG_NAME P3E_CPU0_PE2_SS_TXP<1>
J 0
(2085 4860);
DISPLAY 0.659574 (2085 4860);
PAINT MONO (2085 4860);
DISPLAY INVISIBLE (2085 4860);
FORCEPROP 1 LASTPIN (2075 4850) BN 1
R 1
J 0
(2068 4838);
DISPLAY 0.617021 (2068 4838);
PAINT GREEN (2068 4838);
FORCEPROP 1 LAST PATH I91
J 0
(2073 4900);
DISPLAY 0.872340 (2073 4900);
PAINT GREEN (2073 4900);
DISPLAY INVISIBLE (2073 4900);
FORCEPROP 2 LAST CDS_LIB mstr_standard
J 0
(2075 4900);
PAINT ORANGE (2075 4900);
DISPLAY INVISIBLE (2075 4900);
FORCEPROP 1 LAST BODY_TYPE PLUMBING
J 0
(2125 4850);
DISPLAY 2.276596 (2125 4850);
PAINT GREEN (2125 4850);
DISPLAY INVISIBLE (2125 4850);
FORCEPROP 1 LAST HDL_TAP TRUE
J 0
(2395 4770);
DISPLAY 2.276596 (2395 4770);
PAINT GREEN (2395 4770);
DISPLAY INVISIBLE (2395 4770);
FORCEADD TAP..3
(2275 4900);
FORCEPROP 3 LASTPIN (2275 4850) SIG_NAME P3E_CPU0_PE2_SS_TXP<0>
J 0
(2285 4860);
DISPLAY 0.659574 (2285 4860);
PAINT MONO (2285 4860);
DISPLAY INVISIBLE (2285 4860);
FORCEPROP 1 LASTPIN (2275 4850) BN 0
R 1
J 0
(2268 4838);
DISPLAY 0.617021 (2268 4838);
PAINT GREEN (2268 4838);
FORCEPROP 1 LAST PATH I92
J 0
(2273 4900);
DISPLAY 0.872340 (2273 4900);
PAINT GREEN (2273 4900);
DISPLAY INVISIBLE (2273 4900);
FORCEPROP 2 LAST CDS_LIB mstr_standard
J 0
(2275 4900);
PAINT ORANGE (2275 4900);
DISPLAY INVISIBLE (2275 4900);
FORCEPROP 1 LAST BODY_TYPE PLUMBING
J 0
(2325 4850);
DISPLAY 2.276596 (2325 4850);
PAINT GREEN (2325 4850);
DISPLAY INVISIBLE (2325 4850);
FORCEPROP 1 LAST HDL_TAP TRUE
J 0
(2595 4770);
DISPLAY 2.276596 (2595 4770);
PAINT GREEN (2595 4770);
DISPLAY INVISIBLE (2595 4770);
FORCEADD CAP..1
R 2
(2275 4650);
FORCEPROP 1 LASTPIN (2275 4750) $PN 1
J 2
(2265 4730);
DISPLAY 0.617021 (2265 4730);
PAINT ORANGE (2265 4730);
FORCEPROP 1 LAST MATERIAL X7R
J 2
(2225 4550);
DISPLAY 0.617021 (2225 4550);
PAINT SKYBLUE (2225 4550);
FORCEPROP 1 LAST VOLTAGE 16V
J 2
(2225 4650);
DISPLAY 0.617021 (2225 4650);
PAINT SKYBLUE (2225 4650);
FORCEPROP 1 LAST PACK_TYPE 0402
J 2
(2225 4450);
DISPLAY 0.617021 (2225 4450);
PAINT SKYBLUE (2225 4450);
FORCEPROP 1 LAST TOLERANCE 10%
J 2
(2225 4600);
DISPLAY 0.617021 (2225 4600);
PAINT SKYBLUE (2225 4600);
FORCEPROP 1 LAST VALUE 0.22UF
J 2
(2225 4700);
DISPLAY 0.617021 (2225 4700);
PAINT SKYBLUE (2225 4700);
FORCEPROP 1 LAST LOCATION C8G9
J 2
(2225 4750);
DISPLAY 0.617021 (2225 4750);
PAINT AQUA (2225 4750);
FORCEPROP 1 LAST PART_NUMBER A36096-155
J 2
(2225 4500);
DISPLAY 0.617021 (2225 4500);
PAINT BLUE (2225 4500);
FORCEPROP 1 LASTPIN (2275 4550) $PN 2
J 2
(2265 4530);
DISPLAY 0.617021 (2265 4530);
PAINT ORANGE (2265 4530);
FORCEPROP 2 LAST ROOM OCP_STEERING
J 2
(2275 4650);
PAINT MONO (2275 4650);
DISPLAY INVISIBLE (2275 4650);
FORCEPROP 1 LAST PATH I93
J 2
(2225 4800);
DISPLAY 0.978723 (2225 4800);
PAINT WHITE (2225 4800);
DISPLAY INVISIBLE (2225 4800);
FORCEPROP 2 LAST CDS_LOCATION C8G9
J 2
(2225 4750);
DISPLAY 0.617021 (2225 4750);
PAINT AQUA (2225 4750);
DISPLAY INVISIBLE (2225 4750);
FORCEPROP 2 LAST SEC 1
J 0
(2225 4850);
DISPLAY 0.680851 (2225 4850);
PAINT MONO (2225 4850);
DISPLAY INVISIBLE (2225 4850);
FORCEPROP 2 LAST SEC_TYPE 0402
J 0
(2225 4850);
DISPLAY 1.021277 (2225 4850);
PAINT ORANGE (2225 4850);
DISPLAY INVISIBLE (2225 4850);
FORCEPROP 2 LAST CDS_LIB mstr_discrete
J 0
(2275 4650);
PAINT ORANGE (2275 4650);
DISPLAY INVISIBLE (2275 4650);
FORCEADD TAP..7
(2325 3100);
FORCEPROP 3 LASTPIN (2325 3150) SIG_NAME P3E_CPU0_PE2_SS_C_TXN<0>
J 0
(2335 3160);
DISPLAY 0.659574 (2335 3160);
PAINT MONO (2335 3160);
DISPLAY INVISIBLE (2335 3160);
FORCEPROP 1 LASTPIN (2325 3150) BN 0
R 1
J 0
(2318 3098);
DISPLAY 0.617021 (2318 3098);
PAINT GREEN (2318 3098);
FORCEPROP 1 LAST PATH I94
J 0
(2323 3100);
DISPLAY 0.872340 (2323 3100);
PAINT GREEN (2323 3100);
DISPLAY INVISIBLE (2323 3100);
FORCEPROP 2 LAST CDS_LIB mstr_standard
J 0
(2325 3100);
PAINT ORANGE (2325 3100);
DISPLAY INVISIBLE (2325 3100);
FORCEPROP 1 LAST BODY_TYPE PLUMBING
J 0
(2375 3100);
DISPLAY 2.276596 (2375 3100);
PAINT GREEN (2375 3100);
DISPLAY INVISIBLE (2375 3100);
FORCEPROP 1 LAST HDL_TAP TRUE
J 0
(2645 2970);
DISPLAY 2.276596 (2645 2970);
PAINT GREEN (2645 2970);
DISPLAY INVISIBLE (2645 2970);
FORCEADD OFFPAGE..2
(2550 3050);
FORCEPROP 2 LAST $XR1 245 
J 0
(2859 3050);
DISPLAY 0.638298 (2859 3050);
PAINT MONO (2859 3050);
FORCEPROP 2 LAST $XR0 109 
J 0
(2739 3050);
DISPLAY 0.638298 (2739 3050);
PAINT MONO (2739 3050);
FORCEPROP 2 LAST PATH I95
J 0
(2875 3100);
DISPLAY 1.021277 (2875 3100);
PAINT ORANGE (2875 3100);
DISPLAY INVISIBLE (2875 3100);
FORCEPROP 2 LAST CDS_LIB mstr_standard
J 0
(2550 3050);
PAINT ORANGE (2550 3050);
DISPLAY INVISIBLE (2550 3050);
FORCEPROP 1 LAST OFFPAGE TRUE
J 0
(2875 2925);
DISPLAY 0.872340 (2875 2925);
PAINT GREEN (2875 2925);
DISPLAY INVISIBLE (2875 2925);
FORCEPROP 1 LAST COMMENT_BODY TRUE
J 0
(2505 2955);
DISPLAY 0.872340 (2505 2955);
PAINT GREEN (2505 2955);
DISPLAY INVISIBLE (2505 2955);
FORCEADD CAP..1
R 2
(2325 3650);
FORCEPROP 1 LAST TOLERANCE 10%
J 2
(2275 3600);
DISPLAY 0.617021 (2275 3600);
PAINT SKYBLUE (2275 3600);
FORCEPROP 1 LASTPIN (2325 3750) $PN 1
J 2
(2315 3730);
DISPLAY 0.617021 (2315 3730);
PAINT ORANGE (2315 3730);
FORCEPROP 1 LASTPIN (2325 3550) $PN 2
J 2
(2315 3530);
DISPLAY 0.617021 (2315 3530);
PAINT ORANGE (2315 3530);
FORCEPROP 1 LAST MATERIAL X7R
J 2
(2275 3550);
DISPLAY 0.617021 (2275 3550);
PAINT SKYBLUE (2275 3550);
FORCEPROP 1 LAST VOLTAGE 16V
J 2
(2275 3650);
DISPLAY 0.617021 (2275 3650);
PAINT SKYBLUE (2275 3650);
FORCEPROP 1 LAST PACK_TYPE 0402
J 2
(2275 3450);
DISPLAY 0.617021 (2275 3450);
PAINT SKYBLUE (2275 3450);
FORCEPROP 1 LAST PART_NUMBER A36096-155
J 2
(2275 3500);
DISPLAY 0.617021 (2275 3500);
PAINT BLUE (2275 3500);
FORCEPROP 1 LAST VALUE 0.22UF
J 2
(2275 3700);
DISPLAY 0.617021 (2275 3700);
PAINT SKYBLUE (2275 3700);
FORCEPROP 1 LAST LOCATION C8G10
J 2
(2275 3750);
DISPLAY 0.617021 (2275 3750);
PAINT AQUA (2275 3750);
FORCEPROP 2 LAST ROOM OCP_STEERING
J 2
(2325 3650);
PAINT MONO (2325 3650);
DISPLAY INVISIBLE (2325 3650);
FORCEPROP 1 LAST PATH I96
J 2
(2275 3800);
DISPLAY 0.978723 (2275 3800);
PAINT WHITE (2275 3800);
DISPLAY INVISIBLE (2275 3800);
FORCEPROP 2 LAST CDS_LOCATION C8G10
J 2
(2275 3750);
DISPLAY 0.617021 (2275 3750);
PAINT AQUA (2275 3750);
DISPLAY INVISIBLE (2275 3750);
FORCEPROP 2 LAST SEC 1
J 0
(2275 3850);
DISPLAY 0.680851 (2275 3850);
PAINT MONO (2275 3850);
DISPLAY INVISIBLE (2275 3850);
FORCEPROP 2 LAST SEC_TYPE 0402
J 0
(2275 3850);
DISPLAY 1.021277 (2275 3850);
PAINT ORANGE (2275 3850);
DISPLAY INVISIBLE (2275 3850);
FORCEPROP 2 LAST CDS_LIB mstr_discrete
J 0
(2325 3650);
PAINT ORANGE (2325 3650);
DISPLAY INVISIBLE (2325 3650);
FORCEADD TAP..3
(2325 3900);
FORCEPROP 3 LASTPIN (2325 3850) SIG_NAME P3E_CPU0_PE2_SS_TXN<0>
J 0
(2335 3860);
DISPLAY 0.659574 (2335 3860);
PAINT MONO (2335 3860);
DISPLAY INVISIBLE (2335 3860);
FORCEPROP 1 LASTPIN (2325 3850) BN 0
R 1
J 0
(2318 3838);
DISPLAY 0.617021 (2318 3838);
PAINT GREEN (2318 3838);
FORCEPROP 1 LAST PATH I97
J 0
(2323 3900);
DISPLAY 0.872340 (2323 3900);
PAINT GREEN (2323 3900);
DISPLAY INVISIBLE (2323 3900);
FORCEPROP 2 LAST CDS_LIB mstr_standard
J 0
(2325 3900);
PAINT ORANGE (2325 3900);
DISPLAY INVISIBLE (2325 3900);
FORCEPROP 1 LAST BODY_TYPE PLUMBING
J 0
(2375 3850);
DISPLAY 2.276596 (2375 3850);
PAINT GREEN (2375 3850);
DISPLAY INVISIBLE (2375 3850);
FORCEPROP 1 LAST HDL_TAP TRUE
J 0
(2645 3770);
DISPLAY 2.276596 (2645 3770);
PAINT GREEN (2645 3770);
DISPLAY INVISIBLE (2645 3770);
FORCEADD TAP..7
(2275 4100);
FORCEPROP 3 LASTPIN (2275 4150) SIG_NAME P3E_CPU0_PE2_SS_C_TXP<0>
J 0
(2285 4160);
DISPLAY 0.659574 (2285 4160);
PAINT MONO (2285 4160);
DISPLAY INVISIBLE (2285 4160);
FORCEPROP 1 LASTPIN (2275 4150) BN 0
R 1
J 0
(2268 4098);
DISPLAY 0.617021 (2268 4098);
PAINT GREEN (2268 4098);
FORCEPROP 1 LAST PATH I98
J 0
(2273 4100);
DISPLAY 0.872340 (2273 4100);
PAINT GREEN (2273 4100);
DISPLAY INVISIBLE (2273 4100);
FORCEPROP 2 LAST CDS_LIB mstr_standard
J 0
(2275 4100);
PAINT ORANGE (2275 4100);
DISPLAY INVISIBLE (2275 4100);
FORCEPROP 1 LAST BODY_TYPE PLUMBING
J 0
(2325 4100);
DISPLAY 2.276596 (2325 4100);
PAINT GREEN (2325 4100);
DISPLAY INVISIBLE (2325 4100);
FORCEPROP 1 LAST HDL_TAP TRUE
J 0
(2595 3970);
DISPLAY 2.276596 (2595 3970);
PAINT GREEN (2595 3970);
DISPLAY INVISIBLE (2595 3970);
FORCEADD OFFPAGE..2
(2525 4050);
FORCEPROP 2 LAST $XR1 245 
J 0
(2834 4050);
DISPLAY 0.638298 (2834 4050);
PAINT MONO (2834 4050);
FORCEPROP 2 LAST $XR0 109 
J 0
(2714 4050);
DISPLAY 0.638298 (2714 4050);
PAINT MONO (2714 4050);
FORCEPROP 2 LAST PATH I99
J 0
(2975 4100);
DISPLAY 1.021277 (2975 4100);
PAINT ORANGE (2975 4100);
DISPLAY INVISIBLE (2975 4100);
FORCEPROP 2 LAST CDS_LIB mstr_standard
J 0
(2525 4050);
PAINT ORANGE (2525 4050);
DISPLAY INVISIBLE (2525 4050);
FORCEPROP 1 LAST OFFPAGE TRUE
J 0
(2850 3925);
DISPLAY 0.872340 (2850 3925);
PAINT GREEN (2850 3925);
DISPLAY INVISIBLE (2850 3925);
FORCEPROP 1 LAST COMMENT_BODY TRUE
J 0
(2480 3955);
DISPLAY 0.872340 (2480 3955);
PAINT GREEN (2480 3955);
DISPLAY INVISIBLE (2480 3955);
FORCEADD CAD_NOTE..1
(-2450 3825);
FORCEPROP 0 LAST L2 IF THERE IS NOT ENOUGH ROOM
J 0
(-2575 3625);
DISPLAY 1.021277 (-2575 3625);
PAINT ORANGE (-2575 3625);
FORCEPROP 0 LAST L3 NEAR CPU, PLACE NEAR SLOT
J 0
(-2575 3550);
DISPLAY 1.021277 (-2575 3550);
PAINT ORANGE (-2575 3550);
FORCEPROP 0 LAST L1 PLACE CLOSE TO CPU.
J 0
(-2575 3700);
DISPLAY 1.021277 (-2575 3700);
PAINT ORANGE (-2575 3700);
FORCEPROP 2 LAST CDS_LIB mstr_symbols
J 0
(-2450 3825);
PAINT ORANGE (-2450 3825);
DISPLAY INVISIBLE (-2450 3825);
FORCEPROP 1 LAST COMMENT_BODY TRUE
J 0
(-2425 3925);
DISPLAY 0.978723 (-2425 3925);
PAINT ORANGE (-2425 3925);
DISPLAY INVISIBLE (-2425 3925);
FORCEADD INTEL_CORP_BPAGE..1
(4350 200);
FORCEPROP 1 LAST CDS_CON_LAST_MODIFIED Fri Jun 16 17:48:42 2017
J 0
(2925 525);
PAINT ORANGE (2925 525);
DISPLAY INVISIBLE (2925 525);
FORCEPROP 1 LAST CUSTOM_TXT_CDS <CURRENT_DESIGN_SHEET> OF <TOTAL_DESIGN_SHEETS>
J 0
(3850 225);
PAINT ORANGE (3850 225);
FORCEPROP 1 LAST CUSTOM_TXT_CDS <CON_LAST_MODIFIED>
J 0
(350 300);
PAINT ORANGE (350 300);
FORCEPROP 2 LAST CUSTOM_TXT_CDS <XR_PAGE_TITLE>
J 0
(-3540 5450);
DISPLAY 0.638298 (-3540 5450);
PAINT PINK (-3540 5450);
DISPLAY INVISIBLE (-3540 5450);
FORCEPROP 1 LAST SCH_TITLE PCIE TX CAPS
J 0
(-3600 250);
DISPLAY 1.212766 (-3600 250);
PAINT ORANGE (-3600 250);
FORCEPROP 2 LAST PAGE_BORDER TRUE
J 0
(-3540 5450);
DISPLAY 0.638298 (-3540 5450);
PAINT PINK (-3540 5450);
DISPLAY INVISIBLE (-3540 5450);
FORCEPROP 2 LAST CDS_LIB mstr_symbols
J 0
(4350 200);
PAINT MONO (4350 200);
DISPLAY INVISIBLE (4350 200);
FORCEPROP 1 LAST COMMENT_BODY TRUE
J 0
(4362 212);
DISPLAY 0.468085 (4362 212);
PAINT GREEN (4362 212);
DISPLAY INVISIBLE (4362 212);
FORCEPROP 2 LAST CDS_XR_PAGE_TITLE CR-105 : @BASEBOARD_FAB2_LIB.BASEBOARD_FAB2(SCH_1):PAGE105
J 0
(-3540 5450);
DISPLAY 0.638298 (-3540 5450);
PAINT PINK (-3540 5450);
DISPLAY INVISIBLE (-3540 5450);
WIRE 17 -1 (2650 1725)(2425 1725);
WIRE 17 -1 (2425 1725)(2225 1725);
WIRE 17 -1 (2225 1725)(2025 1725);
WIRE 17 -1 (2025 1725)(1825 1725);
FORCEPROP 2 LAST SIG_NAME P3E_CPU0_PE1_PCH_RXP<15:8>
J 0
(1865 1685);
DISPLAY 0.617021 (1865 1685);
PAINT ORANGE (1865 1685);
WIRE 17 -1 (1825 1725)(1625 1725);
WIRE 17 -1 (1225 1725)(1025 1725);
WIRE 17 -1 (1625 1725)(1425 1725);
WIRE 17 -1 (1425 1725)(1225 1725);
WIRE 17 -1 (2225 1625)(2425 1625);
WIRE 17 -1 (1025 1625)(925 1625);
FORCEPROP 2 LAST SIG_NAME P3E_CPU0_PE1_PCH_R_RXN<15:8>
J 0
(965 1635);
DISPLAY 0.617021 (965 1635);
PAINT ORANGE (965 1635);
WIRE 17 -1 (2225 1625)(2025 1625);
WIRE 17 -1 (2025 1625)(1825 1625);
WIRE 17 -1 (1225 1625)(1025 1625);
WIRE 17 -1 (1425 1625)(1225 1625);
WIRE 17 -1 (1825 1625)(1625 1625);
WIRE 17 -1 (1625 1625)(1425 1625);
WIRE 17 -1 (2175 2625)(2375 2625);
WIRE 17 -1 (2175 2625)(1975 2625);
WIRE 17 -1 (1975 2625)(1775 2625);
WIRE 17 -1 (1775 2625)(1575 2625);
WIRE 17 -1 (1575 2625)(1375 2625);
WIRE 17 -1 (975 2625)(875 2625);
FORCEPROP 2 LAST SIG_NAME P3E_CPU0_PE1_PCH_R_RXP<15:8>
J 0
(915 2635);
DISPLAY 0.617021 (915 2635);
PAINT ORANGE (915 2635);
WIRE 17 -1 (1375 2625)(1175 2625);
WIRE 17 -1 (1175 2625)(975 2625);
WIRE 17 -1 (-675 3050)(-475 3050);
WIRE 17 -1 (-275 3050)(-475 3050);
WIRE 17 -1 (-75 3050)(-275 3050);
WIRE 17 -1 (2500 3050)(2350 3050);
FORCEPROP 2 LAST SIG_NAME P3E_CPU0_PE2_SS_C_TXN<15:0>
J 0
(1850 3010);
DISPLAY 0.617021 (1850 3010);
PAINT ORANGE (1850 3010);
WIRE 17 -1 (125 3050)(-75 3050);
WIRE 17 -1 (325 3050)(125 3050);
WIRE 17 -1 (2350 3050)(2150 3050);
WIRE 17 -1 (2150 3050)(1950 3050);
WIRE 17 -1 (525 3050)(325 3050);
WIRE 17 -1 (725 3050)(525 3050);
WIRE 17 -1 (1950 3050)(1750 3050);
WIRE 17 -1 (1750 3050)(1550 3050);
WIRE 17 -1 (950 3050)(725 3050);
WIRE 17 -1 (1150 3050)(950 3050);
WIRE 17 -1 (1550 3050)(1350 3050);
WIRE 17 -1 (1350 3050)(1150 3050);
WIRE 17 -1 (1075 725)(1275 725);
WIRE 17 -1 (1475 725)(1275 725);
WIRE 17 -1 (1675 725)(1475 725);
WIRE 17 -1 (2700 725)(2475 725);
WIRE 17 -1 (1875 725)(1675 725);
FORCEPROP 2 LAST SIG_NAME P3E_CPU0_PE1_PCH_RXN<15:8>
J 0
(1815 685);
DISPLAY 0.617021 (1815 685);
PAINT ORANGE (1815 685);
WIRE 17 -1 (2075 725)(1875 725);
WIRE 17 -1 (2475 725)(2275 725);
WIRE 17 -1 (2275 725)(2075 725);
WIRE 17 -1 (-2725 1575)(-2825 1575);
FORCEPROP 2 LAST SIG_NAME P3E_CPU0_PE1_PCH_TXP<15:8>
J 0
(-2810 1585);
DISPLAY 0.617021 (-2810 1585);
PAINT ORANGE (-2810 1585);
WIRE 17 -1 (-2525 1575)(-2725 1575);
WIRE 17 -1 (-2325 1575)(-2525 1575);
WIRE 17 -1 (-2125 1575)(-2325 1575);
WIRE 17 -1 (-1925 1575)(-2125 1575);
WIRE 17 -1 (-1725 1575)(-1925 1575);
WIRE 17 -1 (-1525 1575)(-1725 1575);
WIRE 17 -1 (-1525 1575)(-1325 1575);
WIRE 17 -1 (-1100 1675)(-1325 1675);
FORCEPROP 0 LAST SIG_NAME P3E_CPU0_PE1_PCH_C_TXN<15:8>
J 0
(-1985 1635);
DISPLAY 0.617021 (-1985 1635);
PAINT ORANGE (-1985 1635);
WIRE 17 -1 (-2525 1675)(-2725 1675);
WIRE 17 -1 (-1325 1675)(-1525 1675);
WIRE 17 -1 (-1525 1675)(-1725 1675);
WIRE 17 -1 (-2325 1675)(-2525 1675);
WIRE 17 -1 (-2125 1675)(-2325 1675);
WIRE 17 -1 (-1725 1675)(-1925 1675);
WIRE 17 -1 (-1925 1675)(-2125 1675);
WIRE 17 -1 (-775 4950)(-875 4950);
WIRE 17 -1 (-575 4950)(-775 4950);
WIRE 17 -1 (-375 4950)(-575 4950);
WIRE 17 -1 (-175 4950)(-375 4950);
WIRE 17 -1 (25 4950)(-175 4950);
WIRE 17 -1 (225 4950)(25 4950);
FORCEPROP 2 LAST SIG_NAME P3E_CPU0_PE2_SS_TXP<15:0>
J 0
(-850 4960);
DISPLAY 0.617021 (-850 4960);
PAINT ORANGE (-850 4960);
WIRE 17 -1 (425 4950)(225 4950);
WIRE 17 -1 (425 4950)(625 4950);
WIRE 17 -1 (850 4950)(625 4950);
WIRE 17 -1 (1050 4950)(850 4950);
WIRE 17 -1 (2250 4950)(2050 4950);
WIRE 17 -1 (2050 4950)(1850 4950);
WIRE 17 -1 (1250 4950)(1050 4950);
WIRE 17 -1 (1450 4950)(1250 4950);
WIRE 17 -1 (1850 4950)(1650 4950);
WIRE 17 -1 (1650 4950)(1450 4950);
WIRE 17 -1 (-2775 2575)(-2875 2575);
FORCEPROP 2 LAST SIG_NAME P3E_CPU0_PE1_PCH_TXN<15:8>
J 0
(-2860 2585);
DISPLAY 0.617021 (-2860 2585);
PAINT ORANGE (-2860 2585);
WIRE 17 -1 (-2575 2575)(-2775 2575);
WIRE 17 -1 (-2375 2575)(-2575 2575);
WIRE 17 -1 (-2175 2575)(-2375 2575);
WIRE 17 -1 (-1975 2575)(-2175 2575);
WIRE 17 -1 (-1775 2575)(-1975 2575);
WIRE 17 -1 (-1575 2575)(-1775 2575);
WIRE 17 -1 (-1575 2575)(-1375 2575);
WIRE 17 -1 (-525 4050)(-725 4050);
WIRE 17 -1 (-325 4050)(-525 4050);
WIRE 17 -1 (-125 4050)(-325 4050);
WIRE 17 -1 (75 4050)(-125 4050);
WIRE 17 -1 (275 4050)(75 4050);
WIRE 17 -1 (475 4050)(275 4050);
WIRE 17 -1 (675 4050)(475 4050);
WIRE 17 -1 (900 4050)(675 4050);
WIRE 17 -1 (1100 4050)(900 4050);
WIRE 17 -1 (1300 4050)(1100 4050);
WIRE 17 -1 (1500 4050)(1300 4050);
WIRE 17 -1 (1700 4050)(1500 4050);
WIRE 17 -1 (1900 4050)(1700 4050);
WIRE 17 -1 (2100 4050)(1900 4050);
WIRE 17 -1 (2300 4050)(2475 4050);
WIRE 17 -1 (2300 4050)(2100 4050);
FORCEPROP 2 LAST SIG_NAME P3E_CPU0_PE2_SS_C_TXP<15:0>
J 0
(1850 4010);
DISPLAY 0.617021 (1850 4010);
PAINT ORANGE (1850 4010);
WIRE 17 -1 (-725 3950)(-825 3950);
WIRE 17 -1 (-525 3950)(-725 3950);
WIRE 17 -1 (-325 3950)(-525 3950);
WIRE 17 -1 (-125 3950)(-325 3950);
WIRE 17 -1 (75 3950)(-125 3950);
WIRE 17 -1 (275 3950)(75 3950);
FORCEPROP 2 LAST SIG_NAME P3E_CPU0_PE2_SS_TXN<15:0>
J 0
(-800 3960);
DISPLAY 0.617021 (-800 3960);
PAINT ORANGE (-800 3960);
WIRE 17 -1 (475 3950)(275 3950);
WIRE 17 -1 (475 3950)(675 3950);
WIRE 17 -1 (900 3950)(675 3950);
WIRE 17 -1 (1100 3950)(900 3950);
WIRE 17 -1 (1300 3950)(1100 3950);
WIRE 17 -1 (1500 3950)(1300 3950);
WIRE 17 -1 (1700 3950)(1500 3950);
WIRE 17 -1 (1900 3950)(1700 3950);
WIRE 17 -1 (2100 3950)(1900 3950);
WIRE 17 -1 (2300 3950)(2100 3950);
WIRE 17 -1 (-2675 675)(-2475 675);
WIRE 17 -1 (-2275 675)(-2475 675);
WIRE 17 -1 (-2075 675)(-2275 675);
WIRE 17 -1 (-1050 675)(-1275 675);
WIRE 17 -1 (-1875 675)(-2075 675);
FORCEPROP 2 LAST SIG_NAME P3E_CPU0_PE1_PCH_C_TXP<15:8>
J 0
(-1985 635);
DISPLAY 0.617021 (-1985 635);
PAINT ORANGE (-1985 635);
WIRE 17 -1 (-1675 675)(-1875 675);
WIRE 17 -1 (-1275 675)(-1475 675);
WIRE 17 -1 (-1475 675)(-1675 675);
WIRE 16 -1 (1800 1825)(1800 1925);
WIRE 16 -1 (1600 1825)(1600 2225);
WIRE 16 -1 (1400 2525)(1400 2125);
WIRE 16 -1 (-1350 1775)(-1350 2175);
WIRE 16 -1 (-1550 1775)(-1550 1875);
WIRE 16 -1 (-1950 2475)(-1950 2075);
WIRE 16 -1 (-2550 2175)(-2550 1775);
WIRE 16 -1 (-2750 1775)(-2750 1875);
WIRE 16 -1 (-1750 1775)(-1750 2175);
WIRE 16 -1 (-2350 1775)(-2350 1875);
WIRE 16 -1 (-1300 1375)(-1300 1475);
WIRE 16 -1 (-300 3150)(-300 3250);
WIRE 16 -1 (100 3850)(100 3450);
WIRE 16 -1 (2450 825)(2450 1225);
WIRE 16 -1 (1050 1525)(1050 1125);
WIRE 16 -1 (1650 825)(1650 1225);
WIRE 16 -1 (-2300 1475)(-2300 1075);
WIRE 16 -1 (-1900 1475)(-1900 1075);
WIRE 16 -1 (-2500 1175)(-2500 775);
WIRE 16 -1 (1875 4150)(1875 4550);
WIRE 16 -1 (2125 3450)(2125 3850);
WIRE 16 -1 (700 3150)(700 3550);
WIRE 16 -1 (700 3750)(700 3850);
WIRE 16 -1 (650 4150)(650 4550);
WIRE 16 -1 (650 4750)(650 4850);
WIRE 16 -1 (1475 4150)(1475 4550);
WIRE 16 -1 (1075 4550)(1075 4150);
WIRE 16 -1 (875 4850)(875 4450);
WIRE 16 -1 (1675 4850)(1675 4450);
WIRE 16 -1 (450 4450)(450 4850);
WIRE 16 -1 (-150 4850)(-150 4750);
WIRE 16 -1 (925 3850)(925 3450);
WIRE 16 -1 (1125 3850)(1125 3750);
WIRE 16 -1 (2275 4150)(2275 4550);
WIRE 16 -1 (875 4150)(875 4250);
WIRE 16 -1 (500 3450)(500 3850);
WIRE 16 -1 (2325 3150)(2325 3550);
WIRE 16 -1 (300 3750)(300 3850);
WIRE 16 -1 (-700 3150)(-700 3250);
WIRE 16 -1 (-500 3550)(-500 3150);
WIRE 16 -1 (-100 3150)(-100 3550);
WIRE 16 -1 (100 3150)(100 3250);
WIRE 16 -1 (500 3150)(500 3250);
WIRE 16 -1 (300 3150)(300 3550);
WIRE 16 -1 (1325 3150)(1325 3250);
WIRE 16 -1 (1525 3150)(1525 3550);
WIRE 16 -1 (1725 3150)(1725 3250);
WIRE 16 -1 (1925 3150)(1925 3550);
WIRE 16 -1 (2125 3150)(2125 3250);
WIRE 16 -1 (-2700 775)(-2700 875);
WIRE 16 -1 (-2300 775)(-2300 875);
WIRE 16 -1 (-2100 775)(-2100 1175);
WIRE 16 -1 (-2700 1475)(-2700 1075);
WIRE 16 -1 (-2500 1475)(-2500 1375);
WIRE 16 -1 (-2100 1475)(-2100 1375);
WIRE 16 -1 (-2750 2475)(-2750 2075);
WIRE 16 -1 (-2350 2475)(-2350 2075);
WIRE 16 -1 (-2550 2475)(-2550 2375);
WIRE 16 -1 (-2150 2475)(-2150 2375);
WIRE 16 -1 (-1900 775)(-1900 875);
WIRE 16 -1 (-1500 775)(-1500 875);
WIRE 16 -1 (-1300 775)(-1300 1175);
WIRE 16 -1 (-1700 775)(-1700 1175);
WIRE 16 -1 (-1950 1775)(-1950 1875);
WIRE 16 -1 (-700 3850)(-700 3450);
WIRE 16 -1 (-300 3850)(-300 3450);
WIRE 16 -1 (-500 3850)(-500 3750);
WIRE 16 -1 (-100 3850)(-100 3750);
WIRE 16 -1 (-750 4150)(-750 4250);
WIRE 16 -1 (-550 4550)(-550 4150);
WIRE 16 -1 (-750 4850)(-750 4450);
WIRE 16 -1 (-550 4850)(-550 4750);
WIRE 16 -1 (-350 4150)(-350 4250);
WIRE 16 -1 (-150 4150)(-150 4550);
WIRE 16 -1 (-350 4850)(-350 4450);
WIRE 16 -1 (1050 825)(1050 925);
WIRE 16 -1 (1450 825)(1450 925);
WIRE 16 -1 (1850 825)(1850 925);
WIRE 16 -1 (1250 1225)(1250 825);
WIRE 16 -1 (1250 1525)(1250 1425);
WIRE 16 -1 (1400 1825)(1400 1925);
WIRE 16 -1 (1650 1525)(1650 1425);
WIRE 16 -1 (1200 2525)(1200 2425);
WIRE 16 -1 (1600 2525)(1600 2425);
WIRE 16 -1 (2000 2425)(2000 2525);
WIRE 16 -1 (1325 3850)(1325 3450);
WIRE 16 -1 (1525 3850)(1525 3750);
WIRE 16 -1 (1725 3850)(1725 3450);
WIRE 16 -1 (1925 3750)(1925 3850);
WIRE 16 -1 (2050 1425)(2050 1525);
WIRE 16 -1 (2450 1425)(2450 1525);
WIRE 16 -1 (2325 3750)(2325 3850);
WIRE 16 -1 (50 4150)(50 4250);
WIRE 16 -1 (250 4150)(250 4550);
WIRE 16 -1 (450 4150)(450 4250);
WIRE 16 -1 (50 4850)(50 4450);
WIRE 16 -1 (250 4750)(250 4850);
WIRE 16 -1 (1275 4150)(1275 4250);
WIRE 16 -1 (1275 4850)(1275 4450);
WIRE 16 -1 (1075 4850)(1075 4750);
WIRE 16 -1 (1675 4150)(1675 4250);
WIRE 16 -1 (1875 4750)(1875 4850);
WIRE 16 -1 (2075 4150)(2075 4250);
WIRE 16 -1 (2075 4450)(2075 4850);
WIRE 16 -1 (2275 4750)(2275 4850);
WIRE 16 -1 (925 3150)(925 3250);
WIRE 16 -1 (-1750 2375)(-1750 2475);
WIRE 16 -1 (-1550 2075)(-1550 2475);
WIRE 16 -1 (-1350 2375)(-1350 2475);
WIRE 16 -1 (2200 1825)(2200 1925);
WIRE 16 -1 (1475 4850)(1475 4750);
WIRE 16 -1 (-2150 1775)(-2150 2175);
WIRE 16 -1 (-1700 1375)(-1700 1475);
WIRE 16 -1 (-1500 1075)(-1500 1475);
WIRE 16 -1 (2000 1825)(2000 2225);
WIRE 16 -1 (2250 825)(2250 925);
WIRE 16 -1 (2050 825)(2050 1225);
WIRE 16 -1 (2400 1825)(2400 2225);
WIRE 16 -1 (1800 2525)(1800 2125);
WIRE 16 -1 (2200 2125)(2200 2525);
WIRE 16 -1 (2400 2425)(2400 2525);
WIRE 16 -1 (1125 3550)(1125 3150);
WIRE 16 -1 (1000 2525)(1000 2125);
WIRE 16 -1 (2250 1125)(2250 1525);
WIRE 8 682 (-3525 2900)(-3525 600);
WIRE 8 682 (3900 2900)(-3525 2900);
WIRE 8 682 (-3525 600)(3900 600);
WIRE 8 682 (3900 600)(3900 2900);
WIRE 16 -1 (1850 1525)(1850 1125);
WIRE 16 -1 (1450 1525)(1450 1125);
WIRE 16 -1 (1000 1825)(1000 1925);
WIRE 16 -1 (1200 2225)(1200 1825);
FORCENOTE
TO PCH PCIEUP
(-875 1325) 0;
DISPLAY LEFT (-875 1325);
DISPLAY 1.021277 (-875 1325);
PAINT PURPLE (-875 1325);
FORCENOTE
FROM CPU0
(-1575 4100) 0;
DISPLAY LEFT (-1575 4100);
DISPLAY 1.021277 (-1575 4100);
PAINT PURPLE (-1575 4100);
FORCENOTE
TO X24 SLOT
(2825 3750) 0;
DISPLAY LEFT (2825 3750);
DISPLAY 1.021277 (2825 3750);
PAINT PURPLE (2825 3750);
FORCENOTE
DE NOTE:
(-100 5100) 0;
DISPLAY LEFT (-100 5100);
DISPLAY 1.021277 (-100 5100);
PAINT PURPLE (-100 5100);
FORCENOTE
CPU0 TO PCIE X24 SLOT TX CAPS
(-100 5025) 0;
DISPLAY LEFT (-100 5025);
DISPLAY 1.021277 (-100 5025);
PAINT PURPLE (-100 5025);
FORCENOTE
CPU0 TO PCH PCIEUP TX CAPS
(-2650 2700) 0;
DISPLAY LEFT (-2650 2700);
DISPLAY 1.021277 (-2650 2700);
PAINT PURPLE (-2650 2700);
FORCENOTE
FROM CPU0
(-3450 1825) 0;
DISPLAY LEFT (-3450 1825);
DISPLAY 1.021277 (-3450 1825);
PAINT PURPLE (-3450 1825);
FORCENOTE
DE NOTE:
(-2650 2775) 0;
DISPLAY LEFT (-2650 2775);
DISPLAY 1.021277 (-2650 2775);
PAINT PURPLE (-2650 2775);
FORCENOTE
TO CPU0
(3100 1875) 0;
DISPLAY LEFT (3100 1875);
DISPLAY 1.021277 (3100 1875);
PAINT PURPLE (3100 1875);
FORCENOTE
FROM PCH PCIEUP
(50 1800) 0;
DISPLAY LEFT (50 1800);
DISPLAY 1.021277 (50 1800);
PAINT PURPLE (50 1800);
FORCENOTE
C3M3, C3M25, C3M28, C3M36, C3M34, C3M1, C3M12, C3M14, C3M4, C3M26, C3M32, C3M35 AND C3M33
(-3475 2825) 0;
DISPLAY LEFT (-3475 2825);
DISPLAY 1.021277 (-3475 2825);
PAINT PURPLE (-3475 2825);
FORCENOTE
DE NOTE:
(1425 2775) 0;
DISPLAY LEFT (1425 2775);
DISPLAY 1.021277 (1425 2775);
PAINT PURPLE (1425 2775);
FORCENOTE
PCH PCIEUP TO CPU0 RX CAPS
(1425 2700) 0;
DISPLAY LEFT (1425 2700);
DISPLAY 1.021277 (1425 2700);
PAINT PURPLE (1425 2700);
FORCENOTE
PCIE_UPLINK POP: C6B4, C6B6, C6B9, C6B11, C6B14, C6B15, C6B17, C6B19, C6B5, C6B8, C6B10, C6B12, C6B13, C6B16, C6B18, C6B20, C3M2, C3M11, C3M13,
(-3525 2925) 0;
DISPLAY LEFT (-3525 2925);
DISPLAY 1.021277 (-3525 2925);
PAINT PURPLE (-3525 2925);
QUIT
